G04 ================== begin FILE IDENTIFICATION RECORD ==================*
G04 Layout Name:  D:/<user>/Wistron_project/16342-2/gbr/16342-2.brd*
G04 Film Name:    TSMD*
G04 File Format:  Gerber RS274X*
G04 File Origin:  Cadence Allegro 16.5-S056*
G04 Origin Date:  Mon Aug 07 11:24:26 2017*
G04 *
G04 Layer:  VIA CLASS/PASTEMASK_TOP*
G04 Layer:  PIN/PASTEMASK_TOP*
G04 Layer:  PACKAGE GEOMETRY/PASTEMASK_TOP*
G04 Layer:  DRAWING FORMAT/LAYER_PCB_STORY*
G04 Layer:  DRAWING FORMAT/LAYER_PAST_T*
G04 Layer:  BOARD GEOMETRY/PANEL_OUTLINE*
G04 *
G04 Offset:    (0.00 0.00)*
G04 Mirror:    No*
G04 Mode:      Positive*
G04 Rotation:  0*
G04 FullContactRelief:  No*
G04 UndefLineWidth:     6.00*
G04 ================== end FILE IDENTIFICATION RECORD ====================*
%FSLAX35Y35*MOIN*%
%IR0*IPPOS*OFA0.00000B0.00000*MIA0B0*SFA1.00000B1.00000*%
%AMMACRO50*
4,1,40,.013,.017,
-.013,.017,
-.013695,.016939,
-.014368,.016759,
-.015,.016464,
-.015571,.016064,
-.016064,.015571,
-.016464,.015,
-.016759,.014368,
-.016939,.013695,
-.017,.013,
-.017,-.013,
-.016939,-.013695,
-.016759,-.014368,
-.016464,-.015,
-.016064,-.015571,
-.015571,-.016064,
-.015,-.016464,
-.014368,-.016759,
-.013695,-.016939,
-.013,-.017,
.013,-.017,
.013695,-.016939,
.014368,-.016759,
.015,-.016464,
.015571,-.016064,
.016064,-.015571,
.016464,-.015,
.016759,-.014368,
.016939,-.013695,
.017,-.013,
.017,.013,
.016939,.013695,
.016759,.014368,
.016464,.015,
.016064,.015571,
.015571,.016064,
.015,.016464,
.014368,.016759,
.013695,.016939,
.013,.017,
0.0*
%
%ADD50MACRO50*%
%AMMACRO15*
4,1,40,.017,-.013,
.017,.013,
.016939,.013695,
.016759,.014368,
.016464,.015,
.016064,.015571,
.015571,.016064,
.015,.016464,
.014368,.016759,
.013695,.016939,
.013,.017,
-.013,.017,
-.013695,.016939,
-.014368,.016759,
-.015,.016464,
-.015571,.016064,
-.016064,.015571,
-.016464,.015,
-.016759,.014368,
-.016939,.013695,
-.017,.013,
-.017,-.013,
-.016939,-.013695,
-.016759,-.014368,
-.016464,-.015,
-.016064,-.015571,
-.015571,-.016064,
-.015,-.016464,
-.014368,-.016759,
-.013695,-.016939,
-.013,-.017,
.013,-.017,
.013695,-.016939,
.014368,-.016759,
.015,-.016464,
.015571,-.016064,
.016064,-.015571,
.016464,-.015,
.016759,-.014368,
.016939,-.013695,
.017,-.013,
0.0*
%
%ADD15MACRO15*%
%AMMACRO76*
4,1,40,.008,.009,
.008695,.008939,
.009368,.008759,
.01,.008464,
.010571,.008064,
.011064,.007571,
.011464,.007,
.011759,.006368,
.011939,.005695,
.012,.005,
.012,-.005,
.011939,-.005695,
.011759,-.006368,
.011464,-.007,
.011064,-.007571,
.010571,-.008064,
.01,-.008464,
.009368,-.008759,
.008695,-.008939,
.008,-.009,
-.008,-.009,
-.008695,-.008939,
-.009368,-.008759,
-.01,-.008464,
-.010571,-.008064,
-.011064,-.007571,
-.011464,-.007,
-.011759,-.006368,
-.011939,-.005695,
-.012,-.005,
-.012,.005,
-.011939,.005695,
-.011759,.006368,
-.011464,.007,
-.011064,.007571,
-.010571,.008064,
-.01,.008464,
-.009368,.008759,
-.008695,.008939,
-.008,.009,
.008,.009,
0.0*
%
%ADD76MACRO76*%
%AMMACRO61*
4,1,15,-.0275,-.115,
-.0275,.02323,
-.02431,.026923,
-.021809,.031114,
-.020074,.035675,
-.019157,.040469,
-.019087,.045348,
-.019865,.050166,
-.021468,.054776,
-.023847,.059037,
-.02693,.06282,
-.0275,.06339,
-.0275,.115,
.0275,.115,
.0275,-.115,
-.0275,-.115,
0.0*
%
%ADD61MACRO61*%
%AMMACRO47*
4,1,3,.025,.0125,
0.0,-.0125,
-.025,.0125,
.025,.0125,
0.0*
%
%ADD47MACRO47*%
%AMMACRO106*
4,1,3,.0125,0.0,
-.0125,-.025,
-.0125,.025,
.0125,0.0,
0.0*
%
%ADD106MACRO106*%
%AMMACRO97*
4,1,3,0.0,-.0125,
-.025,.0125,
.025,.0125,
0.0,-.0125,
0.0*
%
%ADD97MACRO97*%
%ADD18C,.04*%
%ADD104C,.032*%
%ADD21C,.014*%
%ADD101R,.047X.108*%
%ADD48C,.016*%
%ADD22C,.026*%
%ADD39C,.028*%
%ADD94R,.062X.062*%
%AMMACRO60*
4,1,40,.0225,-.007,
.022378,-.008389,
.022018,-.009736,
.021428,-.011,
.020628,-.012142,
.019642,-.013128,
.0185,-.013928,
.017236,-.014518,
.015889,-.014878,
.0145,-.015,
-.0145,-.015,
-.015889,-.014878,
-.017236,-.014518,
-.0185,-.013928,
-.019642,-.013128,
-.020628,-.012142,
-.021428,-.011,
-.022018,-.009736,
-.022378,-.008389,
-.0225,-.007,
-.0225,.007,
-.022378,.008389,
-.022018,.009736,
-.021428,.011,
-.020628,.012142,
-.019642,.013128,
-.0185,.013928,
-.017236,.014518,
-.015889,.014878,
-.0145,.015,
.0145,.015,
.015889,.014878,
.017236,.014518,
.0185,.013928,
.019642,.013128,
.020628,.012142,
.021428,.011,
.022018,.009736,
.022378,.008389,
.0225,.007,
.0225,-.007,
0.0*
%
%ADD60MACRO60*%
%AMMACRO75*
4,1,40,-.007,-.0225,
-.008389,-.022378,
-.009736,-.022018,
-.011,-.021428,
-.012142,-.020628,
-.013128,-.019642,
-.013928,-.0185,
-.014518,-.017236,
-.014878,-.015889,
-.015,-.0145,
-.015,.0145,
-.014878,.015889,
-.014518,.017236,
-.013928,.0185,
-.013128,.019642,
-.012142,.020628,
-.011,.021428,
-.009736,.022018,
-.008389,.022378,
-.007,.0225,
.007,.0225,
.008389,.022378,
.009736,.022018,
.011,.021428,
.012142,.020628,
.013128,.019642,
.013928,.0185,
.014518,.017236,
.014878,.015889,
.015,.0145,
.015,-.0145,
.014878,-.015889,
.014518,-.017236,
.013928,-.0185,
.013128,-.019642,
.012142,-.020628,
.011,-.021428,
.009736,-.022018,
.008389,-.022378,
.007,-.0225,
-.007,-.0225,
0.0*
%
%ADD75MACRO75*%
%AMMACRO30*
4,1,40,.011,-.007,
.011,.007,
.010939,.007695,
.010759,.008368,
.010464,.009,
.010064,.009571,
.009571,.010064,
.009,.010464,
.008368,.010759,
.007695,.010939,
.007,.011,
-.007,.011,
-.007695,.010939,
-.008368,.010759,
-.009,.010464,
-.009571,.010064,
-.010064,.009571,
-.010464,.009,
-.010759,.008368,
-.010939,.007695,
-.011,.007,
-.011,-.007,
-.010939,-.007695,
-.010759,-.008368,
-.010464,-.009,
-.010064,-.009571,
-.009571,-.010064,
-.009,-.010464,
-.008368,-.010759,
-.007695,-.010939,
-.007,-.011,
.007,-.011,
.007695,-.010939,
.008368,-.010759,
.009,-.010464,
.009571,-.010064,
.010064,-.009571,
.010464,-.009,
.010759,-.008368,
.010939,-.007695,
.011,-.007,
0.0*
%
%ADD30MACRO30*%
%AMMACRO12*
4,1,40,.007,.011,
-.007,.011,
-.007695,.010939,
-.008368,.010759,
-.009,.010464,
-.009571,.010064,
-.010064,.009571,
-.010464,.009,
-.010759,.008368,
-.010939,.007695,
-.011,.007,
-.011,-.007,
-.010939,-.007695,
-.010759,-.008368,
-.010464,-.009,
-.010064,-.009571,
-.009571,-.010064,
-.009,-.010464,
-.008368,-.010759,
-.007695,-.010939,
-.007,-.011,
.007,-.011,
.007695,-.010939,
.008368,-.010759,
.009,-.010464,
.009571,-.010064,
.010064,-.009571,
.010464,-.009,
.010759,-.008368,
.010939,-.007695,
.011,-.007,
.011,.007,
.010939,.007695,
.010759,.008368,
.010464,.009,
.010064,.009571,
.009571,.010064,
.009,.010464,
.008368,.010759,
.007695,.010939,
.007,.011,
0.0*
%
%ADD12MACRO12*%
%AMMACRO24*
4,1,40,-.012,.008,
-.012,-.008,
-.011939,-.008695,
-.011759,-.009368,
-.011464,-.01,
-.011064,-.010571,
-.010571,-.011064,
-.01,-.011464,
-.009368,-.011759,
-.008695,-.011939,
-.008,-.012,
.008,-.012,
.008695,-.011939,
.009368,-.011759,
.01,-.011464,
.010571,-.011064,
.011064,-.010571,
.011464,-.01,
.011759,-.009368,
.011939,-.008695,
.012,-.008,
.012,.008,
.011939,.008695,
.011759,.009368,
.011464,.01,
.011064,.010571,
.010571,.011064,
.01,.011464,
.009368,.011759,
.008695,.011939,
.008,.012,
-.008,.012,
-.008695,.011939,
-.009368,.011759,
-.01,.011464,
-.010571,.011064,
-.011064,.010571,
-.011464,.01,
-.011759,.009368,
-.011939,.008695,
-.012,.008,
0.0*
%
%ADD24MACRO24*%
%AMMACRO35*
4,1,40,.008,.012,
-.008,.012,
-.008695,.011939,
-.009368,.011759,
-.01,.011464,
-.010571,.011064,
-.011064,.010571,
-.011464,.01,
-.011759,.009368,
-.011939,.008695,
-.012,.008,
-.012,-.008,
-.011939,-.008695,
-.011759,-.009368,
-.011464,-.01,
-.011064,-.010571,
-.010571,-.011064,
-.01,-.011464,
-.009368,-.011759,
-.008695,-.011939,
-.008,-.012,
.008,-.012,
.008695,-.011939,
.009368,-.011759,
.01,-.011464,
.010571,-.011064,
.011064,-.010571,
.011464,-.01,
.011759,-.009368,
.011939,-.008695,
.012,-.008,
.012,.008,
.011939,.008695,
.011759,.009368,
.011464,.01,
.011064,.010571,
.010571,.011064,
.01,.011464,
.009368,.011759,
.008695,.011939,
.008,.012,
0.0*
%
%ADD35MACRO35*%
%AMMACRO57*
4,1,40,-.013,-.017,
.013,-.017,
.013695,-.016939,
.014368,-.016759,
.015,-.016464,
.015571,-.016064,
.016064,-.015571,
.016464,-.015,
.016759,-.014368,
.016939,-.013695,
.017,-.013,
.017,.013,
.016939,.013695,
.016759,.014368,
.016464,.015,
.016064,.015571,
.015571,.016064,
.015,.016464,
.014368,.016759,
.013695,.016939,
.013,.017,
-.013,.017,
-.013695,.016939,
-.014368,.016759,
-.015,.016464,
-.015571,.016064,
-.016064,.015571,
-.016464,.015,
-.016759,.014368,
-.016939,.013695,
-.017,.013,
-.017,-.013,
-.016939,-.013695,
-.016759,-.014368,
-.016464,-.015,
-.016064,-.015571,
-.015571,-.016064,
-.015,-.016464,
-.014368,-.016759,
-.013695,-.016939,
-.013,-.017,
0.0*
%
%ADD57MACRO57*%
%AMMACRO66*
4,1,40,-.009,.008,
-.008939,.008695,
-.008759,.009368,
-.008464,.01,
-.008064,.010571,
-.007571,.011064,
-.007,.011464,
-.006368,.011759,
-.005695,.011939,
-.005,.012,
.005,.012,
.005695,.011939,
.006368,.011759,
.007,.011464,
.007571,.011064,
.008064,.010571,
.008464,.01,
.008759,.009368,
.008939,.008695,
.009,.008,
.009,-.008,
.008939,-.008695,
.008759,-.009368,
.008464,-.01,
.008064,-.010571,
.007571,-.011064,
.007,-.011464,
.006368,-.011759,
.005695,-.011939,
.005,-.012,
-.005,-.012,
-.005695,-.011939,
-.006368,-.011759,
-.007,-.011464,
-.007571,-.011064,
-.008064,-.010571,
-.008464,-.01,
-.008759,-.009368,
-.008939,-.008695,
-.009,-.008,
-.009,.008,
0.0*
%
%ADD66MACRO66*%
%AMMACRO40*
4,1,40,-.017,.013,
-.017,-.013,
-.016939,-.013695,
-.016759,-.014368,
-.016464,-.015,
-.016064,-.015571,
-.015571,-.016064,
-.015,-.016464,
-.014368,-.016759,
-.013695,-.016939,
-.013,-.017,
.013,-.017,
.013695,-.016939,
.014368,-.016759,
.015,-.016464,
.015571,-.016064,
.016064,-.015571,
.016464,-.015,
.016759,-.014368,
.016939,-.013695,
.017,-.013,
.017,.013,
.016939,.013695,
.016759,.014368,
.016464,.015,
.016064,.015571,
.015571,.016064,
.015,.016464,
.014368,.016759,
.013695,.016939,
.013,.017,
-.013,.017,
-.013695,.016939,
-.014368,.016759,
-.015,.016464,
-.015571,.016064,
-.016064,.015571,
-.016464,.015,
-.016759,.014368,
-.016939,.013695,
-.017,.013,
0.0*
%
%ADD40MACRO40*%
%AMMACRO79*
4,1,40,.008,.009,
.008695,.008939,
.009368,.008759,
.01,.008464,
.010571,.008064,
.011064,.007571,
.011464,.007,
.011759,.006368,
.011939,.005695,
.012,.005,
.012,-.005,
.011939,-.005695,
.011759,-.006368,
.011464,-.007,
.011064,-.007571,
.010571,-.008064,
.01,-.008464,
.009368,-.008759,
.008695,-.008939,
.008,-.009,
-.008,-.009,
-.008695,-.008939,
-.009368,-.008759,
-.01,-.008464,
-.010571,-.008064,
-.011064,-.007571,
-.011464,-.007,
-.011759,-.006368,
-.011939,-.005695,
-.012,-.005,
-.012,.005,
-.011939,.005695,
-.011759,.006368,
-.011464,.007,
-.011064,.007571,
-.010571,.008064,
-.01,.008464,
-.009368,.008759,
-.008695,.008939,
-.008,.009,
.008,.009,
0.0*
%
%ADD79MACRO79*%
%AMMACRO31*
4,1,40,.011,-.007,
.011,.007,
.010939,.007695,
.010759,.008368,
.010464,.009,
.010064,.009571,
.009571,.010064,
.009,.010464,
.008368,.010759,
.007695,.010939,
.007,.011,
-.007,.011,
-.007695,.010939,
-.008368,.010759,
-.009,.010464,
-.009571,.010064,
-.010064,.009571,
-.010464,.009,
-.010759,.008368,
-.010939,.007695,
-.011,.007,
-.011,-.007,
-.010939,-.007695,
-.010759,-.008368,
-.010464,-.009,
-.010064,-.009571,
-.009571,-.010064,
-.009,-.010464,
-.008368,-.010759,
-.007695,-.010939,
-.007,-.011,
.007,-.011,
.007695,-.010939,
.008368,-.010759,
.009,-.010464,
.009571,-.010064,
.010064,-.009571,
.010464,-.009,
.010759,-.008368,
.010939,-.007695,
.011,-.007,
0.0*
%
%ADD31MACRO31*%
%AMMACRO13*
4,1,40,.007,.011,
-.007,.011,
-.007695,.010939,
-.008368,.010759,
-.009,.010464,
-.009571,.010064,
-.010064,.009571,
-.010464,.009,
-.010759,.008368,
-.010939,.007695,
-.011,.007,
-.011,-.007,
-.010939,-.007695,
-.010759,-.008368,
-.010464,-.009,
-.010064,-.009571,
-.009571,-.010064,
-.009,-.010464,
-.008368,-.010759,
-.007695,-.010939,
-.007,-.011,
.007,-.011,
.007695,-.010939,
.008368,-.010759,
.009,-.010464,
.009571,-.010064,
.010064,-.009571,
.010464,-.009,
.010759,-.008368,
.010939,-.007695,
.011,-.007,
.011,.007,
.010939,.007695,
.010759,.008368,
.010464,.009,
.010064,.009571,
.009571,.010064,
.009,.010464,
.008368,.010759,
.007695,.010939,
.007,.011,
0.0*
%
%ADD13MACRO13*%
%AMMACRO23*
4,1,40,-.012,.008,
-.012,-.008,
-.011939,-.008695,
-.011759,-.009368,
-.011464,-.01,
-.011064,-.010571,
-.010571,-.011064,
-.01,-.011464,
-.009368,-.011759,
-.008695,-.011939,
-.008,-.012,
.008,-.012,
.008695,-.011939,
.009368,-.011759,
.01,-.011464,
.010571,-.011064,
.011064,-.010571,
.011464,-.01,
.011759,-.009368,
.011939,-.008695,
.012,-.008,
.012,.008,
.011939,.008695,
.011759,.009368,
.011464,.01,
.011064,.010571,
.010571,.011064,
.01,.011464,
.009368,.011759,
.008695,.011939,
.008,.012,
-.008,.012,
-.008695,.011939,
-.009368,.011759,
-.01,.011464,
-.010571,.011064,
-.011064,.010571,
-.011464,.01,
-.011759,.009368,
-.011939,.008695,
-.012,.008,
0.0*
%
%ADD23MACRO23*%
%AMMACRO34*
4,1,40,.008,.012,
-.008,.012,
-.008695,.011939,
-.009368,.011759,
-.01,.011464,
-.010571,.011064,
-.011064,.010571,
-.011464,.01,
-.011759,.009368,
-.011939,.008695,
-.012,.008,
-.012,-.008,
-.011939,-.008695,
-.011759,-.009368,
-.011464,-.01,
-.011064,-.010571,
-.010571,-.011064,
-.01,-.011464,
-.009368,-.011759,
-.008695,-.011939,
-.008,-.012,
.008,-.012,
.008695,-.011939,
.009368,-.011759,
.01,-.011464,
.010571,-.011064,
.011064,-.010571,
.011464,-.01,
.011759,-.009368,
.011939,-.008695,
.012,-.008,
.012,.008,
.011939,.008695,
.011759,.009368,
.011464,.01,
.011064,.010571,
.010571,.011064,
.01,.011464,
.009368,.011759,
.008695,.011939,
.008,.012,
0.0*
%
%ADD34MACRO34*%
%AMMACRO58*
4,1,40,-.013,-.017,
.013,-.017,
.013695,-.016939,
.014368,-.016759,
.015,-.016464,
.015571,-.016064,
.016064,-.015571,
.016464,-.015,
.016759,-.014368,
.016939,-.013695,
.017,-.013,
.017,.013,
.016939,.013695,
.016759,.014368,
.016464,.015,
.016064,.015571,
.015571,.016064,
.015,.016464,
.014368,.016759,
.013695,.016939,
.013,.017,
-.013,.017,
-.013695,.016939,
-.014368,.016759,
-.015,.016464,
-.015571,.016064,
-.016064,.015571,
-.016464,.015,
-.016759,.014368,
-.016939,.013695,
-.017,.013,
-.017,-.013,
-.016939,-.013695,
-.016759,-.014368,
-.016464,-.015,
-.016064,-.015571,
-.015571,-.016064,
-.015,-.016464,
-.014368,-.016759,
-.013695,-.016939,
-.013,-.017,
0.0*
%
%ADD58MACRO58*%
%AMMACRO65*
4,1,40,.009,-.008,
.008939,-.008695,
.008759,-.009368,
.008464,-.01,
.008064,-.010571,
.007571,-.011064,
.007,-.011464,
.006368,-.011759,
.005695,-.011939,
.005,-.012,
-.005,-.012,
-.005695,-.011939,
-.006368,-.011759,
-.007,-.011464,
-.007571,-.011064,
-.008064,-.010571,
-.008464,-.01,
-.008759,-.009368,
-.008939,-.008695,
-.009,-.008,
-.009,.008,
-.008939,.008695,
-.008759,.009368,
-.008464,.01,
-.008064,.010571,
-.007571,.011064,
-.007,.011464,
-.006368,.011759,
-.005695,.011939,
-.005,.012,
.005,.012,
.005695,.011939,
.006368,.011759,
.007,.011464,
.007571,.011064,
.008064,.010571,
.008464,.01,
.008759,.009368,
.008939,.008695,
.009,.008,
.009,-.008,
0.0*
%
%ADD65MACRO65*%
%AMMACRO41*
4,1,40,-.017,.013,
-.017,-.013,
-.016939,-.013695,
-.016759,-.014368,
-.016464,-.015,
-.016064,-.015571,
-.015571,-.016064,
-.015,-.016464,
-.014368,-.016759,
-.013695,-.016939,
-.013,-.017,
.013,-.017,
.013695,-.016939,
.014368,-.016759,
.015,-.016464,
.015571,-.016064,
.016064,-.015571,
.016464,-.015,
.016759,-.014368,
.016939,-.013695,
.017,-.013,
.017,.013,
.016939,.013695,
.016759,.014368,
.016464,.015,
.016064,.015571,
.015571,.016064,
.015,.016464,
.014368,.016759,
.013695,.016939,
.013,.017,
-.013,.017,
-.013695,.016939,
-.014368,.016759,
-.015,.016464,
-.015571,.016064,
-.016064,.015571,
-.016464,.015,
-.016759,.014368,
-.016939,.013695,
-.017,.013,
0.0*
%
%ADD41MACRO41*%
%AMMACRO78*
4,1,40,-.008,-.009,
-.008695,-.008939,
-.009368,-.008759,
-.01,-.008464,
-.010571,-.008064,
-.011064,-.007571,
-.011464,-.007,
-.011759,-.006368,
-.011939,-.005695,
-.012,-.005,
-.012,.005,
-.011939,.005695,
-.011759,.006368,
-.011464,.007,
-.011064,.007571,
-.010571,.008064,
-.01,.008464,
-.009368,.008759,
-.008695,.008939,
-.008,.009,
.008,.009,
.008695,.008939,
.009368,.008759,
.01,.008464,
.010571,.008064,
.011064,.007571,
.011464,.007,
.011759,.006368,
.011939,.005695,
.012,.005,
.012,-.005,
.011939,-.005695,
.011759,-.006368,
.011464,-.007,
.011064,-.007571,
.010571,-.008064,
.01,-.008464,
.009368,-.008759,
.008695,-.008939,
.008,-.009,
-.008,-.009,
0.0*
%
%ADD78MACRO78*%
%AMMACRO107*
4,1,3,.0125,-.025,
-.0125,0.0,
.0125,.025,
.0125,-.025,
0.0*
%
%ADD107MACRO107*%
%AMMACRO98*
4,1,3,-.025,-.0125,
0.0,.0125,
.025,-.0125,
-.025,-.0125,
0.0*
%
%ADD98MACRO98*%
%ADD82R,.012X.05*%
%ADD74R,.05X.012*%
%ADD64R,.06X.02*%
%ADD88R,.042X.012*%
%ADD86R,.012X.042*%
%ADD71R,.06X.012*%
%AMMACRO46*
4,1,3,0.0,.0125,
.025,-.0125,
-.025,-.0125,
0.0,.0125,
0.0*
%
%ADD46MACRO46*%
%ADD16R,.022X.04*%
%ADD81R,.012X.043*%
%ADD73R,.043X.012*%
%ADD111R,.128X.13*%
%ADD102R,.012X.061*%
%ADD70R,.06X.014*%
%ADD68R,.081X.02*%
%ADD56R,.04X.016*%
%ADD45R,.044X.012*%
%ADD29R,.042X.014*%
%ADD28R,.014X.042*%
%ADD108R,.012X.044*%
%ADD100R,.014X.06*%
%ADD87R,.036X.012*%
%ADD85R,.012X.036*%
%ADD55R,.105X.128*%
%ADD103R,.016X.032*%
%ADD96R,.037X.012*%
%ADD95R,.012X.037*%
%ADD93R,.064X.03*%
%ADD91R,.03X.045*%
%ADD110R,.128X.133*%
%ADD33R,.066X.02*%
%ADD17R,.05X.065*%
%ADD84R,.055X.042*%
%ADD77R,.026X.036*%
%ADD32R,.065X.025*%
%ADD92R,.09X.045*%
%ADD72R,.048X.016*%
%ADD67R,.025X.065*%
%ADD38R,.045X.055*%
%ADD89R,.13X.13*%
%ADD59R,.016X.048*%
%ADD37R,.055X.045*%
%ADD36R,.055X.036*%
%ADD109R,.09X.095*%
%ADD69R,.059X.045*%
%ADD52R,.024X.079*%
%ADD90R,.045X.059*%
%ADD83R,.152X.152*%
%AMMACRO63*
4,1,40,-.0225,.007,
-.022378,.008389,
-.022018,.009736,
-.021428,.011,
-.020628,.012142,
-.019642,.013128,
-.0185,.013928,
-.017236,.014518,
-.015889,.014878,
-.0145,.015,
.0145,.015,
.015889,.014878,
.017236,.014518,
.0185,.013928,
.019642,.013128,
.020628,.012142,
.021428,.011,
.022018,.009736,
.022378,.008389,
.0225,.007,
.0225,-.007,
.022378,-.008389,
.022018,-.009736,
.021428,-.011,
.020628,-.012142,
.019642,-.013128,
.0185,-.013928,
.017236,-.014518,
.015889,-.014878,
.0145,-.015,
-.0145,-.015,
-.015889,-.014878,
-.017236,-.014518,
-.0185,-.013928,
-.019642,-.013128,
-.020628,-.012142,
-.021428,-.011,
-.022018,-.009736,
-.022378,-.008389,
-.0225,-.007,
-.0225,.007,
0.0*
%
%ADD63MACRO63*%
%AMMACRO62*
4,1,40,.014,.008,
.014,-.008,
.013939,-.008695,
.013759,-.009368,
.013464,-.01,
.013064,-.010571,
.012571,-.011064,
.012,-.011464,
.011368,-.011759,
.010695,-.011939,
.01,-.012,
-.01,-.012,
-.010695,-.011939,
-.011368,-.011759,
-.012,-.011464,
-.012571,-.011064,
-.013064,-.010571,
-.013464,-.01,
-.013759,-.009368,
-.013939,-.008695,
-.014,-.008,
-.014,.008,
-.013939,.008695,
-.013759,.009368,
-.013464,.01,
-.013064,.010571,
-.012571,.011064,
-.012,.011464,
-.011368,.011759,
-.010695,.011939,
-.01,.012,
.01,.012,
.010695,.011939,
.011368,.011759,
.012,.011464,
.012571,.011064,
.013064,.010571,
.013464,.01,
.013759,.009368,
.013939,.008695,
.014,.008,
0.0*
%
%ADD62MACRO62*%
%ADD54R,.095X.09*%
%ADD99R,.083X.069*%
%ADD27R,.128X.128*%
%AMMACRO43*
4,1,40,-.008,-.012,
.008,-.012,
.008695,-.011939,
.009368,-.011759,
.01,-.011464,
.010571,-.011064,
.011064,-.010571,
.011464,-.01,
.011759,-.009368,
.011939,-.008695,
.012,-.008,
.012,.008,
.011939,.008695,
.011759,.009368,
.011464,.01,
.011064,.010571,
.010571,.011064,
.01,.011464,
.009368,.011759,
.008695,.011939,
.008,.012,
-.008,.012,
-.008695,.011939,
-.009368,.011759,
-.01,.011464,
-.010571,.011064,
-.011064,.010571,
-.011464,.01,
-.011759,.009368,
-.011939,.008695,
-.012,.008,
-.012,-.008,
-.011939,-.008695,
-.011759,-.009368,
-.011464,-.01,
-.011064,-.010571,
-.010571,-.011064,
-.01,-.011464,
-.009368,-.011759,
-.008695,-.011939,
-.008,-.012,
0.0*
%
%ADD43MACRO43*%
%AMMACRO26*
4,1,40,.012,-.008,
.012,.008,
.011939,.008695,
.011759,.009368,
.011464,.01,
.011064,.010571,
.010571,.011064,
.01,.011464,
.009368,.011759,
.008695,.011939,
.008,.012,
-.008,.012,
-.008695,.011939,
-.009368,.011759,
-.01,.011464,
-.010571,.011064,
-.011064,.010571,
-.011464,.01,
-.011759,.009368,
-.011939,.008695,
-.012,.008,
-.012,-.008,
-.011939,-.008695,
-.011759,-.009368,
-.011464,-.01,
-.011064,-.010571,
-.010571,-.011064,
-.01,-.011464,
-.009368,-.011759,
-.008695,-.011939,
-.008,-.012,
.008,-.012,
.008695,-.011939,
.009368,-.011759,
.01,-.011464,
.010571,-.011064,
.011064,-.010571,
.011464,-.01,
.011759,-.009368,
.011939,-.008695,
.012,-.008,
0.0*
%
%ADD26MACRO26*%
%AMMACRO19*
4,1,40,-.007,-.011,
.007,-.011,
.007695,-.010939,
.008368,-.010759,
.009,-.010464,
.009571,-.010064,
.010064,-.009571,
.010464,-.009,
.010759,-.008368,
.010939,-.007695,
.011,-.007,
.011,.007,
.010939,.007695,
.010759,.008368,
.010464,.009,
.010064,.009571,
.009571,.010064,
.009,.010464,
.008368,.010759,
.007695,.010939,
.007,.011,
-.007,.011,
-.007695,.010939,
-.008368,.010759,
-.009,.010464,
-.009571,.010064,
-.010064,.009571,
-.010464,.009,
-.010759,.008368,
-.010939,.007695,
-.011,.007,
-.011,-.007,
-.010939,-.007695,
-.010759,-.008368,
-.010464,-.009,
-.010064,-.009571,
-.009571,-.010064,
-.009,-.010464,
-.008368,-.010759,
-.007695,-.010939,
-.007,-.011,
0.0*
%
%ADD19MACRO19*%
%AMMACRO10*
4,1,40,-.011,.007,
-.011,-.007,
-.010939,-.007695,
-.010759,-.008368,
-.010464,-.009,
-.010064,-.009571,
-.009571,-.010064,
-.009,-.010464,
-.008368,-.010759,
-.007695,-.010939,
-.007,-.011,
.007,-.011,
.007695,-.010939,
.008368,-.010759,
.009,-.010464,
.009571,-.010064,
.010064,-.009571,
.010464,-.009,
.010759,-.008368,
.010939,-.007695,
.011,-.007,
.011,.007,
.010939,.007695,
.010759,.008368,
.010464,.009,
.010064,.009571,
.009571,.010064,
.009,.010464,
.008368,.010759,
.007695,.010939,
.007,.011,
-.007,.011,
-.007695,.010939,
-.008368,.010759,
-.009,.010464,
-.009571,.010064,
-.010064,.009571,
-.010464,.009,
-.010759,.008368,
-.010939,.007695,
-.011,.007,
0.0*
%
%ADD10MACRO10*%
%AMMACRO49*
4,1,40,.013,.017,
-.013,.017,
-.013695,.016939,
-.014368,.016759,
-.015,.016464,
-.015571,.016064,
-.016064,.015571,
-.016464,.015,
-.016759,.014368,
-.016939,.013695,
-.017,.013,
-.017,-.013,
-.016939,-.013695,
-.016759,-.014368,
-.016464,-.015,
-.016064,-.015571,
-.015571,-.016064,
-.015,-.016464,
-.014368,-.016759,
-.013695,-.016939,
-.013,-.017,
.013,-.017,
.013695,-.016939,
.014368,-.016759,
.015,-.016464,
.015571,-.016064,
.016064,-.015571,
.016464,-.015,
.016759,-.014368,
.016939,-.013695,
.017,-.013,
.017,.013,
.016939,.013695,
.016759,.014368,
.016464,.015,
.016064,.015571,
.015571,.016064,
.015,.016464,
.014368,.016759,
.013695,.016939,
.013,.017,
0.0*
%
%ADD49MACRO49*%
%AMMACRO14*
4,1,40,.017,-.013,
.017,.013,
.016939,.013695,
.016759,.014368,
.016464,.015,
.016064,.015571,
.015571,.016064,
.015,.016464,
.014368,.016759,
.013695,.016939,
.013,.017,
-.013,.017,
-.013695,.016939,
-.014368,.016759,
-.015,.016464,
-.015571,.016064,
-.016064,.015571,
-.016464,.015,
-.016759,.014368,
-.016939,.013695,
-.017,.013,
-.017,-.013,
-.016939,-.013695,
-.016759,-.014368,
-.016464,-.015,
-.016064,-.015571,
-.015571,-.016064,
-.015,-.016464,
-.014368,-.016759,
-.013695,-.016939,
-.013,-.017,
.013,-.017,
.013695,-.016939,
.014368,-.016759,
.015,-.016464,
.015571,-.016064,
.016064,-.015571,
.016464,-.015,
.016759,-.014368,
.016939,-.013695,
.017,-.013,
0.0*
%
%ADD14MACRO14*%
%AMMACRO80*
4,1,40,-.008,-.009,
-.008695,-.008939,
-.009368,-.008759,
-.01,-.008464,
-.010571,-.008064,
-.011064,-.007571,
-.011464,-.007,
-.011759,-.006368,
-.011939,-.005695,
-.012,-.005,
-.012,.005,
-.011939,.005695,
-.011759,.006368,
-.011464,.007,
-.011064,.007571,
-.010571,.008064,
-.01,.008464,
-.009368,.008759,
-.008695,.008939,
-.008,.009,
.008,.009,
.008695,.008939,
.009368,.008759,
.01,.008464,
.010571,.008064,
.011064,.007571,
.011464,.007,
.011759,.006368,
.011939,.005695,
.012,.005,
.012,-.005,
.011939,-.005695,
.011759,-.006368,
.011464,-.007,
.011064,-.007571,
.010571,-.008064,
.01,-.008464,
.009368,-.008759,
.008695,-.008939,
.008,-.009,
-.008,-.009,
0.0*
%
%ADD80MACRO80*%
%AMMACRO105*
4,1,20,.1075,.0635,
.1075,.049,
.118,.049,
.118,.0395,
.1075,.0395,
.1075,-.0395,
.118,-.0395,
.118,-.049,
.1075,-.049,
.1075,-.0635,
-.1075,-.0635,
-.1075,-.049,
-.118,-.049,
-.118,-.0395,
-.1075,-.0395,
-.1075,.0395,
-.118,.0395,
-.118,.049,
-.1075,.049,
-.1075,.0635,
.1075,.0635,
0.0*
%
%ADD105MACRO105*%
%AMMACRO44*
4,1,20,-.0635,.1075,
-.049,.1075,
-.049,.118,
-.0395,.118,
-.0395,.1075,
.0395,.1075,
.0395,.118,
.049,.118,
.049,.1075,
.0635,.1075,
.0635,-.1075,
.049,-.1075,
.049,-.118,
.0395,-.118,
.0395,-.1075,
-.0395,-.1075,
-.0395,-.118,
-.049,-.118,
-.049,-.1075,
-.0635,-.1075,
-.0635,.1075,
0.0*
%
%ADD44MACRO44*%
%AMMACRO51*
4,1,15,-.0275,-.115,
-.0275,.115,
.0275,.115,
.0275,.06339,
.02431,.059697,
.021809,.055506,
.020074,.050945,
.019157,.046151,
.019087,.041272,
.019865,.036454,
.021468,.031844,
.023847,.027583,
.02693,.0238,
.0275,.02323,
.0275,-.115,
-.0275,-.115,
0.0*
%
%ADD51MACRO51*%
%AMMACRO42*
4,1,40,-.008,-.012,
.008,-.012,
.008695,-.011939,
.009368,-.011759,
.01,-.011464,
.010571,-.011064,
.011064,-.010571,
.011464,-.01,
.011759,-.009368,
.011939,-.008695,
.012,-.008,
.012,.008,
.011939,.008695,
.011759,.009368,
.011464,.01,
.011064,.010571,
.010571,.011064,
.01,.011464,
.009368,.011759,
.008695,.011939,
.008,.012,
-.008,.012,
-.008695,.011939,
-.009368,.011759,
-.01,.011464,
-.010571,.011064,
-.011064,.010571,
-.011464,.01,
-.011759,.009368,
-.011939,.008695,
-.012,.008,
-.012,-.008,
-.011939,-.008695,
-.011759,-.009368,
-.011464,-.01,
-.011064,-.010571,
-.010571,-.011064,
-.01,-.011464,
-.009368,-.011759,
-.008695,-.011939,
-.008,-.012,
0.0*
%
%ADD42MACRO42*%
%AMMACRO25*
4,1,40,.012,-.008,
.012,.008,
.011939,.008695,
.011759,.009368,
.011464,.01,
.011064,.010571,
.010571,.011064,
.01,.011464,
.009368,.011759,
.008695,.011939,
.008,.012,
-.008,.012,
-.008695,.011939,
-.009368,.011759,
-.01,.011464,
-.010571,.011064,
-.011064,.010571,
-.011464,.01,
-.011759,.009368,
-.011939,.008695,
-.012,.008,
-.012,-.008,
-.011939,-.008695,
-.011759,-.009368,
-.011464,-.01,
-.011064,-.010571,
-.010571,-.011064,
-.01,-.011464,
-.009368,-.011759,
-.008695,-.011939,
-.008,-.012,
.008,-.012,
.008695,-.011939,
.009368,-.011759,
.01,-.011464,
.010571,-.011064,
.011064,-.010571,
.011464,-.01,
.011759,-.009368,
.011939,-.008695,
.012,-.008,
0.0*
%
%ADD25MACRO25*%
%AMMACRO20*
4,1,40,-.007,-.011,
.007,-.011,
.007695,-.010939,
.008368,-.010759,
.009,-.010464,
.009571,-.010064,
.010064,-.009571,
.010464,-.009,
.010759,-.008368,
.010939,-.007695,
.011,-.007,
.011,.007,
.010939,.007695,
.010759,.008368,
.010464,.009,
.010064,.009571,
.009571,.010064,
.009,.010464,
.008368,.010759,
.007695,.010939,
.007,.011,
-.007,.011,
-.007695,.010939,
-.008368,.010759,
-.009,.010464,
-.009571,.010064,
-.010064,.009571,
-.010464,.009,
-.010759,.008368,
-.010939,.007695,
-.011,.007,
-.011,-.007,
-.010939,-.007695,
-.010759,-.008368,
-.010464,-.009,
-.010064,-.009571,
-.009571,-.010064,
-.009,-.010464,
-.008368,-.010759,
-.007695,-.010939,
-.007,-.011,
0.0*
%
%ADD20MACRO20*%
%AMMACRO11*
4,1,40,-.011,.007,
-.011,-.007,
-.010939,-.007695,
-.010759,-.008368,
-.010464,-.009,
-.010064,-.009571,
-.009571,-.010064,
-.009,-.010464,
-.008368,-.010759,
-.007695,-.010939,
-.007,-.011,
.007,-.011,
.007695,-.010939,
.008368,-.010759,
.009,-.010464,
.009571,-.010064,
.010064,-.009571,
.010464,-.009,
.010759,-.008368,
.010939,-.007695,
.011,-.007,
.011,.007,
.010939,.007695,
.010759,.008368,
.010464,.009,
.010064,.009571,
.009571,.010064,
.009,.010464,
.008368,.010759,
.007695,.010939,
.007,.011,
-.007,.011,
-.007695,.010939,
-.008368,.010759,
-.009,.010464,
-.009571,.010064,
-.010064,.009571,
-.010464,.009,
-.010759,.008368,
-.010939,.007695,
-.011,.007,
0.0*
%
%ADD11MACRO11*%
%ADD112C,.02*%
%ADD113C,.006*%
G75*
%LPD*%
G75*
G36*
G01X535408Y30333D02*
Y21783D01*
X544358D01*
Y30333D01*
X535408D01*
G37*
G36*
G01Y41483D02*
Y32933D01*
X544358D01*
Y41483D01*
X535408D01*
G37*
G36*
G01X546958Y30333D02*
Y21783D01*
X555908D01*
Y30333D01*
X546958D01*
G37*
G36*
G01Y41483D02*
Y32933D01*
X555908D01*
Y41483D01*
X546958D01*
G37*
G54D100*
X714454Y422965D03*
Y406785D03*
X717014Y422965D03*
X719574D03*
X722134D03*
Y406785D03*
X719574D03*
X717014D03*
X797354Y421965D03*
X799914D03*
X802474D03*
X805034D03*
Y405785D03*
X802474D03*
X799914D03*
X797354D03*
G54D110*
X882622Y129353D03*
Y164275D03*
G54D101*
X665551Y527953D03*
X763976D03*
X747047D03*
X845472D03*
G54D102*
X714173Y501279D03*
X712205D03*
X710236D03*
X708268D03*
X706299D03*
X704330D03*
X702362D03*
X700393D03*
X698425D03*
X696456D03*
X694488D03*
X692519D03*
X690551D03*
X688582D03*
X686614D03*
X684645D03*
X682677D03*
X680708D03*
X678740D03*
X676771D03*
X674803D03*
X672834D03*
X670866D03*
X713189Y531004D03*
X711220D03*
X709252D03*
X707283D03*
X705315D03*
X703346D03*
X701378D03*
X699409D03*
X697441D03*
X695472D03*
X693504D03*
X691535D03*
X689567D03*
X687598D03*
X685630D03*
X683661D03*
X681693D03*
X679724D03*
X677756D03*
X675787D03*
X673819D03*
X671850D03*
X669882D03*
X785039Y501279D03*
X783070D03*
X781102D03*
X779133D03*
X777165D03*
X775196D03*
X773228D03*
X771259D03*
X769291D03*
X786023Y531004D03*
X784055D03*
X782086D03*
X780118D03*
X778149D03*
X776181D03*
X774212D03*
X772244D03*
X770275D03*
X768307D03*
X741732Y501279D03*
X739764D03*
X737795D03*
X735827D03*
X725984D03*
X724016D03*
X722047D03*
X720079D03*
X718110D03*
X716142D03*
X742716Y531004D03*
X740748D03*
X738779D03*
X736811D03*
X734842D03*
X725000D03*
X723031D03*
X721063D03*
X719094D03*
X717126D03*
X715157D03*
X840157Y501279D03*
X838189D03*
X836220D03*
X834252D03*
X824409D03*
X822441D03*
X820472D03*
X818504D03*
X816535D03*
X814567D03*
X812598D03*
X810630D03*
X808661D03*
X806693D03*
X804724D03*
X802755D03*
X800787D03*
X798818D03*
X796850D03*
X794881D03*
X792913D03*
X790944D03*
X788976D03*
X787007D03*
X841141Y531004D03*
X839173D03*
X837204D03*
X835236D03*
X833267D03*
X823425D03*
X821456D03*
X819488D03*
X817519D03*
X815551D03*
X813582D03*
X811614D03*
X809645D03*
X807677D03*
X805708D03*
X803740D03*
X801771D03*
X799803D03*
X797834D03*
X795866D03*
X793897D03*
X791929D03*
X789960D03*
X787992D03*
G54D111*
X877456Y322390D03*
Y357012D03*
G54D112*
G01X-36569Y-23804D02*
Y-103804D01*
G01D02*
X1258031D01*
G01X-40569Y-7804D02*
G02I-12000J0D01*
G01X-45719D02*
G02I-6850J0D01*
G01X-52569Y-23804D02*
Y8196D01*
G01X-36569Y-23804D02*
X1258031D01*
G01X-36569Y-59304D02*
X1258031D01*
G01X-36569Y-7804D02*
X-68569D01*
G01X470531Y-23804D02*
Y-103804D01*
G01X608031Y-23804D02*
Y-103804D01*
G01X723031Y-23804D02*
Y-103804D01*
G01X890531Y-23804D02*
Y-103804D01*
G01X1060531Y-23804D02*
Y-103804D01*
G01X1258031Y-23804D02*
Y-103804D01*
G01X1286031Y-7804D02*
G02I-12000J0D01*
G01X1280881D02*
G02I-6850J0D01*
G01X1274031Y-23804D02*
Y8196D01*
G01X1290031Y-7804D02*
X1258031D01*
G54D10*
X38500Y49800D03*
X48200Y675584D03*
X78268Y60055D03*
X104000Y478800D03*
X108500Y487300D03*
X104000D03*
X108277Y570651D03*
X111200Y709900D03*
X86028Y689739D03*
X81928Y689839D03*
X174588Y489713D03*
X187167Y502984D03*
X198700Y516900D03*
X203500D03*
X212600Y517000D03*
X141914Y519838D03*
X182648Y503054D03*
X204100Y638000D03*
X142572Y633732D03*
X150872D03*
X166500Y633800D03*
X157458Y633832D03*
X145279Y619170D03*
X172700Y622700D03*
X176800D03*
X180985D03*
X185085D03*
X189185D03*
X193285D03*
X149400Y623200D03*
X154300Y703515D03*
X168047Y705075D03*
X151749Y695715D03*
X164249D03*
X210123Y655596D03*
X267514Y540585D03*
X243700Y552100D03*
X229342Y514955D03*
X223400Y638000D03*
X238000Y621800D03*
X234000D03*
X221900Y623700D03*
X229952Y626430D03*
X225900Y623700D03*
X251900Y613400D03*
X243900D03*
X262823Y624696D03*
X236000Y639200D03*
X225984Y659043D03*
X258431Y704824D03*
X246700Y675900D03*
X247500Y702300D03*
X214723Y652096D03*
X343582Y178478D03*
X347882Y271078D03*
X346819Y520675D03*
X350400Y528500D03*
X341226Y528509D03*
X334827Y517153D03*
X304617Y589881D03*
X299000Y658100D03*
X289612Y661529D03*
X291700Y730200D03*
X287620Y730220D03*
X374883Y181153D03*
X359481Y484466D03*
X384300Y548400D03*
X361120Y585686D03*
X374600Y583400D03*
X464342Y53858D03*
X468400Y61300D03*
X472700Y61200D03*
X443489Y42401D03*
X594541Y29581D03*
X590347Y57307D03*
X703300Y21800D03*
X713200Y390800D03*
X712851Y474882D03*
X712000Y435400D03*
X718300Y390800D03*
X725200Y435400D03*
X754800Y527000D03*
X854596Y159135D03*
X841625Y177777D03*
X846077Y152224D03*
X838627Y378815D03*
X846456Y354057D03*
X834984Y371069D03*
X796100Y389800D03*
X801200D03*
X811099Y473779D03*
X794900Y434400D03*
X808100D03*
G54D103*
X775160Y23465D03*
X772600D03*
X770040D03*
Y31535D03*
X772600D03*
X775160D03*
G54D113*
G01X-9023Y-84471D02*
X-8149Y-83596D01*
X-7494Y-82138D01*
X-7057Y-80095D01*
X-7494Y-78346D01*
X-8367Y-77179D01*
X-9896Y-76304D01*
X-15791D01*
Y-93804D01*
X-8586D01*
X-7057Y-92638D01*
X-6184Y-90887D01*
X-5747Y-88846D01*
X-6184Y-86804D01*
X-7494Y-85054D01*
X-9023Y-84471D01*
X-15791D01*
G01X3674Y-93804D02*
Y-82138D01*
G01Y-84471D02*
X4766Y-83304D01*
X5858Y-82429D01*
X7386Y-82138D01*
X8477Y-82429D01*
X9788Y-83304D01*
G01X19646Y-99054D02*
X20956Y-99637D01*
X22703Y-99054D01*
X23794Y-97888D01*
X24668Y-96429D01*
X25977Y-91763D01*
X28816Y-82138D01*
G01X21829D02*
X25977Y-91763D01*
G01X45224Y-83596D02*
X43696Y-82429D01*
X42386Y-82138D01*
X40639Y-82721D01*
X39329Y-83887D01*
X38456Y-85929D01*
X38237Y-87971D01*
X38456Y-90013D01*
X39329Y-91763D01*
X40639Y-93221D01*
X42386Y-93804D01*
X43914Y-93221D01*
X45224Y-92054D01*
G01X55956Y-85929D02*
X62943D01*
X62288Y-83887D01*
X61196Y-82721D01*
X59668Y-82138D01*
X58139Y-82429D01*
X56829Y-83304D01*
X55956Y-85346D01*
X55519Y-87096D01*
Y-88846D01*
X55956Y-90596D01*
X57048Y-92346D01*
X58358Y-93512D01*
X59886Y-93804D01*
X61414Y-93221D01*
X62943Y-91471D01*
G01X99034Y-77763D02*
X97724Y-76887D01*
X96196Y-76304D01*
X94449D01*
X92484Y-77179D01*
X90956Y-78637D01*
X89864Y-80388D01*
X88991Y-83304D01*
X88772Y-85929D01*
X89209Y-88554D01*
X89864Y-90304D01*
X91174Y-92054D01*
X92703Y-93221D01*
X94231Y-93804D01*
X95759D01*
X97288Y-93221D01*
X98598Y-92346D01*
X99690Y-91180D01*
G01X115661Y-93804D02*
Y-82138D01*
G01Y-84179D02*
X114788Y-83013D01*
X113477Y-82429D01*
X111949Y-82138D01*
X110421Y-82721D01*
X109111Y-83887D01*
X108237Y-85637D01*
X107801Y-87971D01*
X108237Y-90304D01*
X109111Y-92054D01*
X110421Y-93221D01*
X111949Y-93804D01*
X113477Y-93512D01*
X114788Y-92638D01*
X115661Y-91471D01*
G01X125519Y-93804D02*
Y-82138D01*
G01Y-85054D02*
X126393Y-83596D01*
X127703Y-82429D01*
X129449Y-82138D01*
X130977Y-82429D01*
X132288Y-83596D01*
X132943Y-85637D01*
Y-93804D01*
G01X142146Y-99054D02*
X143456Y-99637D01*
X145203Y-99054D01*
X146294Y-97888D01*
X147168Y-96429D01*
X148477Y-91763D01*
X151316Y-82138D01*
G01X144329D02*
X148477Y-91763D01*
G01X164231Y-93804D02*
X162921Y-93512D01*
X161611Y-92346D01*
X160737Y-90304D01*
X160301Y-87971D01*
X160737Y-85637D01*
X161611Y-83596D01*
X162921Y-82429D01*
X164231Y-82138D01*
X165541Y-82429D01*
X166851Y-83596D01*
X167724Y-85637D01*
X167943Y-87971D01*
X167724Y-90304D01*
X166851Y-92346D01*
X165541Y-93512D01*
X164231Y-93804D01*
G01X178019D02*
Y-82138D01*
G01Y-85054D02*
X178893Y-83596D01*
X180203Y-82429D01*
X181949Y-82138D01*
X183477Y-82429D01*
X184788Y-83596D01*
X185443Y-85637D01*
Y-93804D01*
G01X214111Y-76304D02*
X219351D01*
G01X216731D02*
Y-93804D01*
G01X214111D02*
X219351D01*
G01X234231D02*
X232484Y-93512D01*
X230956Y-92346D01*
X229646Y-90596D01*
X228772Y-88554D01*
X228336Y-86221D01*
Y-83887D01*
X228772Y-81554D01*
X229646Y-79512D01*
X230956Y-77763D01*
X232484Y-76596D01*
X234231Y-76304D01*
X235977Y-76596D01*
X237506Y-77763D01*
X238816Y-79512D01*
X239690Y-81554D01*
X240126Y-83887D01*
Y-86221D01*
X239690Y-88554D01*
X238816Y-90596D01*
X237506Y-92346D01*
X235977Y-93512D01*
X234231Y-93804D01*
G01X246054D02*
Y-76304D01*
X251731Y-90887D01*
X257408Y-76304D01*
Y-93804D01*
G01X285639Y-99637D02*
X283456Y-96721D01*
X282364Y-93804D01*
Y-82138D01*
X283456Y-79221D01*
X285639Y-76304D01*
G01X298554Y-93804D02*
Y-76304D01*
X304231Y-90887D01*
X309908Y-76304D01*
Y-93804D01*
G01X321731Y-94387D02*
X321294Y-94096D01*
Y-93512D01*
X321731Y-93221D01*
X322168Y-93512D01*
Y-94096D01*
X321731Y-94387D01*
G01X335083Y-79221D02*
X336393Y-77471D01*
X337921Y-76596D01*
X339668Y-76304D01*
X341851Y-76887D01*
X343379Y-78346D01*
X343816Y-80095D01*
X343598Y-81846D01*
X342724Y-83304D01*
X338358Y-86221D01*
X336393Y-88262D01*
X335083Y-91180D01*
X334646Y-93804D01*
X343816D01*
G01X374231D02*
X372921Y-93512D01*
X371611Y-92346D01*
X370737Y-90304D01*
X370301Y-87971D01*
X370737Y-85637D01*
X371611Y-83596D01*
X372921Y-82429D01*
X374231Y-82138D01*
X375541Y-82429D01*
X376851Y-83596D01*
X377724Y-85637D01*
X377943Y-87971D01*
X377724Y-90304D01*
X376851Y-92346D01*
X375541Y-93512D01*
X374231Y-93804D01*
G01X388019D02*
Y-82138D01*
G01Y-85054D02*
X388893Y-83596D01*
X390203Y-82429D01*
X391949Y-82138D01*
X393477Y-82429D01*
X394788Y-83596D01*
X395443Y-85637D01*
Y-93804D01*
G01X409231D02*
Y-76304D01*
G01X422146Y-99054D02*
X423456Y-99637D01*
X425203Y-99054D01*
X426294Y-97888D01*
X427168Y-96429D01*
X428477Y-91763D01*
X431316Y-82138D01*
G01X424329D02*
X428477Y-91763D01*
G01X445323Y-99637D02*
X447506Y-96721D01*
X448598Y-93804D01*
Y-82138D01*
X447506Y-79221D01*
X445323Y-76304D01*
G01X176054Y-48804D02*
Y-31304D01*
X181731Y-45887D01*
X187408Y-31304D01*
Y-48804D01*
G01X199231D02*
X197921Y-48512D01*
X196611Y-47346D01*
X195737Y-45304D01*
X195301Y-42971D01*
X195737Y-40637D01*
X196611Y-38596D01*
X197921Y-37429D01*
X199231Y-37138D01*
X200541Y-37429D01*
X201851Y-38596D01*
X202724Y-40637D01*
X202943Y-42971D01*
X202724Y-45304D01*
X201851Y-47346D01*
X200541Y-48512D01*
X199231Y-48804D01*
G01X220661Y-31304D02*
Y-48804D01*
G01Y-46180D02*
X219788Y-47638D01*
X218477Y-48512D01*
X216949Y-48804D01*
X215203Y-48221D01*
X213893Y-46763D01*
X213019Y-45013D01*
X212801Y-42971D01*
X213019Y-40929D01*
X213893Y-39179D01*
X215203Y-37721D01*
X216949Y-37138D01*
X218477Y-37429D01*
X219569Y-38013D01*
X220661Y-39179D01*
G01X230956Y-40929D02*
X237943D01*
X237288Y-38887D01*
X236196Y-37721D01*
X234668Y-37138D01*
X233139Y-37429D01*
X231829Y-38304D01*
X230956Y-40346D01*
X230519Y-42096D01*
Y-43846D01*
X230956Y-45596D01*
X232048Y-47346D01*
X233358Y-48512D01*
X234886Y-48804D01*
X236414Y-48221D01*
X237943Y-46471D01*
G01X251731Y-48804D02*
Y-31304D01*
G01X504231Y-93804D02*
Y-76304D01*
X501611Y-79804D01*
G01Y-93804D02*
X506851D01*
G01X517583Y-86513D02*
X519111Y-84471D01*
X520421Y-83304D01*
X522168Y-82721D01*
X523696Y-83304D01*
X524788Y-84471D01*
X525661Y-86221D01*
X525879Y-88262D01*
X525661Y-90013D01*
X524788Y-91763D01*
X523477Y-93221D01*
X521949Y-93804D01*
X520203Y-93221D01*
X518674Y-91471D01*
X517801Y-88846D01*
X517583Y-85929D01*
X518019Y-82138D01*
X518674Y-80095D01*
X519766Y-78054D01*
X521294Y-76596D01*
X522823Y-76304D01*
X524351Y-76887D01*
X525443Y-78346D01*
G01X534428Y-90304D02*
X535737Y-92346D01*
X537484Y-93512D01*
X539449Y-93804D01*
X541196Y-93512D01*
X542943Y-92054D01*
X544034Y-90304D01*
X544253Y-88554D01*
X543816Y-86513D01*
X542288Y-85054D01*
X540759Y-84471D01*
X538794D01*
G01X540759D02*
X542069Y-83596D01*
X543161Y-82138D01*
X543598Y-80388D01*
X543161Y-78637D01*
X542069Y-77179D01*
X540104Y-76304D01*
X538139Y-76596D01*
X536174Y-77763D01*
G01X559351Y-93804D02*
Y-76304D01*
X551272Y-88846D01*
X562190D01*
G01X570083Y-79221D02*
X571393Y-77471D01*
X572921Y-76596D01*
X574668Y-76304D01*
X576851Y-76887D01*
X578379Y-78346D01*
X578816Y-80095D01*
X578598Y-81846D01*
X577724Y-83304D01*
X573358Y-86221D01*
X571393Y-88262D01*
X570083Y-91180D01*
X569646Y-93804D01*
X578816D01*
G01X491114Y-48804D02*
Y-31304D01*
X496354D01*
X498101Y-32179D01*
X499411Y-34221D01*
X499848Y-36554D01*
X499411Y-38887D01*
X498319Y-40637D01*
X496354Y-41513D01*
X491114D01*
G01X517784Y-32763D02*
X516474Y-31887D01*
X514946Y-31304D01*
X513199D01*
X511234Y-32179D01*
X509706Y-33637D01*
X508614Y-35388D01*
X507741Y-38304D01*
X507522Y-40929D01*
X507959Y-43554D01*
X508614Y-45304D01*
X509924Y-47054D01*
X511453Y-48221D01*
X512981Y-48804D01*
X514509D01*
X516038Y-48221D01*
X517348Y-47346D01*
X518440Y-46180D01*
G01X532227Y-39471D02*
X533101Y-38596D01*
X533756Y-37138D01*
X534193Y-35095D01*
X533756Y-33346D01*
X532883Y-32179D01*
X531354Y-31304D01*
X525459D01*
Y-48804D01*
X532664D01*
X534193Y-47638D01*
X535066Y-45887D01*
X535503Y-43846D01*
X535066Y-41804D01*
X533756Y-40054D01*
X532227Y-39471D01*
X525459D01*
G01X541431Y-54637D02*
X554531D01*
G01X560459Y-48804D02*
Y-31304D01*
X570503Y-48804D01*
Y-31304D01*
G01X582981Y-48804D02*
X581234Y-48512D01*
X579706Y-47346D01*
X578396Y-45596D01*
X577522Y-43554D01*
X577086Y-41221D01*
Y-38887D01*
X577522Y-36554D01*
X578396Y-34512D01*
X579706Y-32763D01*
X581234Y-31596D01*
X582981Y-31304D01*
X584727Y-31596D01*
X586256Y-32763D01*
X587566Y-34512D01*
X588440Y-36554D01*
X588876Y-38887D01*
Y-41221D01*
X588440Y-43554D01*
X587566Y-45596D01*
X586256Y-47346D01*
X584727Y-48512D01*
X582981Y-48804D01*
G01X633822Y-31304D02*
X639281Y-48804D01*
X644740Y-31304D01*
G01X661148Y-48804D02*
X652414D01*
Y-31304D01*
X661148D01*
G01X657654Y-39762D02*
X652414D01*
G01X669914Y-48804D02*
Y-31304D01*
X675373D01*
X677119Y-32179D01*
X678211Y-33346D01*
X678648Y-35679D01*
X678211Y-38013D01*
X676901Y-39471D01*
X675373Y-40346D01*
X669914D01*
G01X675373D02*
X678648Y-48804D01*
G01X691781Y-49387D02*
X691344Y-49096D01*
Y-48512D01*
X691781Y-48221D01*
X692218Y-48512D01*
Y-49096D01*
X691781Y-49387D01*
G01X661383Y-79221D02*
X662693Y-77471D01*
X664221Y-76596D01*
X665968Y-76304D01*
X668151Y-76887D01*
X669679Y-78346D01*
X670116Y-80095D01*
X669898Y-81846D01*
X669024Y-83304D01*
X664658Y-86221D01*
X662693Y-88262D01*
X661383Y-91180D01*
X660946Y-93804D01*
X670116D01*
G01X780481Y-76304D02*
Y-93804D01*
G01X775459Y-76304D02*
X785503D01*
G01X793396Y-91471D02*
X795143Y-92929D01*
X797108Y-93804D01*
X798854D01*
X800601Y-92929D01*
X801911Y-91471D01*
X802566Y-89429D01*
X802129Y-87388D01*
X801038Y-85637D01*
X799073Y-84471D01*
X796453Y-83887D01*
X794924Y-82721D01*
X794269Y-80679D01*
X794706Y-78637D01*
X795798Y-77179D01*
X797326Y-76304D01*
X798854D01*
X800383Y-76887D01*
X801693Y-78346D01*
G01X809804Y-93804D02*
Y-76304D01*
X815481Y-90887D01*
X821158Y-76304D01*
Y-93804D01*
G01X828178D02*
Y-76304D01*
X832544D01*
X834291Y-77179D01*
X835601Y-78346D01*
X836693Y-80095D01*
X837566Y-82138D01*
X837784Y-85054D01*
X837566Y-87971D01*
X836693Y-90013D01*
X835601Y-91763D01*
X834291Y-92929D01*
X832544Y-93804D01*
X828178D01*
G01X767364Y-31304D02*
Y-48804D01*
X776098D01*
G01X793161D02*
Y-37138D01*
G01Y-39179D02*
X792288Y-38013D01*
X790977Y-37429D01*
X789449Y-37138D01*
X787921Y-37721D01*
X786611Y-38887D01*
X785737Y-40637D01*
X785301Y-42971D01*
X785737Y-45304D01*
X786611Y-47054D01*
X787921Y-48221D01*
X789449Y-48804D01*
X790977Y-48512D01*
X792288Y-47638D01*
X793161Y-46471D01*
G01X802146Y-54054D02*
X803456Y-54637D01*
X805203Y-54054D01*
X806294Y-52888D01*
X807168Y-51429D01*
X808477Y-46763D01*
X811316Y-37138D01*
G01X804329D02*
X808477Y-46763D01*
G01X820956Y-40929D02*
X827943D01*
X827288Y-38887D01*
X826196Y-37721D01*
X824668Y-37138D01*
X823139Y-37429D01*
X821829Y-38304D01*
X820956Y-40346D01*
X820519Y-42096D01*
Y-43846D01*
X820956Y-45596D01*
X822048Y-47346D01*
X823358Y-48512D01*
X824886Y-48804D01*
X826414Y-48221D01*
X827943Y-46471D01*
G01X838674Y-48804D02*
Y-37138D01*
G01Y-39471D02*
X839766Y-38304D01*
X840858Y-37429D01*
X842386Y-37138D01*
X843477Y-37429D01*
X844788Y-38304D01*
G01X931781Y-93804D02*
X930034Y-93512D01*
X928506Y-92346D01*
X927196Y-90596D01*
X926322Y-88554D01*
X925886Y-86221D01*
Y-83887D01*
X926322Y-81554D01*
X927196Y-79512D01*
X928506Y-77763D01*
X930034Y-76596D01*
X931781Y-76304D01*
X933527Y-76596D01*
X935056Y-77763D01*
X936366Y-79512D01*
X937240Y-81554D01*
X937676Y-83887D01*
Y-86221D01*
X937240Y-88554D01*
X936366Y-90596D01*
X935056Y-92346D01*
X933527Y-93512D01*
X931781Y-93804D01*
G01X933527Y-89137D02*
X936148Y-93804D01*
G01X944478Y-76304D02*
Y-88846D01*
X945351Y-91471D01*
X947098Y-93221D01*
X949281Y-93804D01*
X951464Y-93221D01*
X953211Y-91471D01*
X954084Y-88846D01*
Y-76304D01*
G01X964161D02*
X969401D01*
G01X966781D02*
Y-93804D01*
G01X964161D02*
X969401D01*
G01X979259D02*
Y-76304D01*
X989303Y-93804D01*
Y-76304D01*
G01X1006584Y-77763D02*
X1005274Y-76887D01*
X1003746Y-76304D01*
X1001999D01*
X1000034Y-77179D01*
X998506Y-78637D01*
X997414Y-80388D01*
X996541Y-83304D01*
X996322Y-85929D01*
X996759Y-88554D01*
X997414Y-90304D01*
X998724Y-92054D01*
X1000253Y-93221D01*
X1001781Y-93804D01*
X1003309D01*
X1004838Y-93221D01*
X1006148Y-92346D01*
X1007240Y-91180D01*
G01X1019281Y-93804D02*
Y-85929D01*
X1014914Y-76304D01*
G01X1023648D02*
X1019281Y-85929D01*
G01X909478Y-48804D02*
Y-31304D01*
X913844D01*
X915591Y-32179D01*
X916901Y-33346D01*
X917993Y-35095D01*
X918866Y-37138D01*
X919084Y-40054D01*
X918866Y-42971D01*
X917993Y-45013D01*
X916901Y-46763D01*
X915591Y-47929D01*
X913844Y-48804D01*
X909478D01*
G01X928506Y-40929D02*
X935493D01*
X934838Y-38887D01*
X933746Y-37721D01*
X932218Y-37138D01*
X930689Y-37429D01*
X929379Y-38304D01*
X928506Y-40346D01*
X928069Y-42096D01*
Y-43846D01*
X928506Y-45596D01*
X929598Y-47346D01*
X930908Y-48512D01*
X932436Y-48804D01*
X933964Y-48221D01*
X935493Y-46471D01*
G01X946006Y-46763D02*
X947098Y-47929D01*
X948626Y-48804D01*
X949936D01*
X951246Y-48221D01*
X952119Y-47346D01*
X952556Y-46180D01*
X952338Y-44429D01*
X951464Y-43554D01*
X947534Y-41804D01*
X946661Y-39762D01*
X947098Y-38304D01*
X947971Y-37429D01*
X949281Y-37138D01*
X950591Y-37429D01*
X951901Y-38304D01*
G01X966781Y-37138D02*
Y-48804D01*
G01Y-32471D02*
X966344Y-32179D01*
Y-31596D01*
X966781Y-31304D01*
X967218Y-31596D01*
Y-32179D01*
X966781Y-32471D01*
G01X981224Y-53179D02*
X982753Y-54346D01*
X984499Y-54637D01*
X986027Y-54346D01*
X987338Y-52888D01*
X988211Y-50846D01*
Y-37138D01*
G01Y-39471D02*
X987338Y-38304D01*
X986027Y-37429D01*
X984499Y-37138D01*
X982753Y-37721D01*
X981661Y-38887D01*
X980787Y-40929D01*
X980351Y-42971D01*
X980569Y-44721D01*
X981443Y-46763D01*
X982753Y-48221D01*
X984499Y-48804D01*
X985809Y-48512D01*
X987338Y-47346D01*
X988211Y-46180D01*
G01X998069Y-48804D02*
Y-37138D01*
G01Y-40054D02*
X998943Y-38596D01*
X1000253Y-37429D01*
X1001999Y-37138D01*
X1003527Y-37429D01*
X1004838Y-38596D01*
X1005493Y-40637D01*
Y-48804D01*
G01X1016006Y-40929D02*
X1022993D01*
X1022338Y-38887D01*
X1021246Y-37721D01*
X1019718Y-37138D01*
X1018189Y-37429D01*
X1016879Y-38304D01*
X1016006Y-40346D01*
X1015569Y-42096D01*
Y-43846D01*
X1016006Y-45596D01*
X1017098Y-47346D01*
X1018408Y-48512D01*
X1019936Y-48804D01*
X1021464Y-48221D01*
X1022993Y-46471D01*
G01X1033724Y-48804D02*
Y-37138D01*
G01Y-39471D02*
X1034816Y-38304D01*
X1035908Y-37429D01*
X1037436Y-37138D01*
X1038527Y-37429D01*
X1039838Y-38304D01*
G01X1080481Y-76304D02*
X1078734Y-76887D01*
X1077424Y-78346D01*
X1076551Y-80095D01*
X1075896Y-82429D01*
X1075678Y-85054D01*
X1075896Y-87679D01*
X1076551Y-90013D01*
X1077424Y-91763D01*
X1078734Y-93221D01*
X1080481Y-93804D01*
X1082227Y-93221D01*
X1083538Y-91763D01*
X1084411Y-90013D01*
X1085066Y-87679D01*
X1085284Y-85054D01*
X1085066Y-82429D01*
X1084411Y-80095D01*
X1083538Y-78346D01*
X1082227Y-76887D01*
X1080481Y-76304D01*
G01X1097981Y-93804D02*
X1099509Y-93512D01*
X1101256Y-92638D01*
X1102348Y-91180D01*
X1102784Y-89137D01*
X1102348Y-87096D01*
X1101038Y-85346D01*
X1099073Y-84471D01*
X1096889D01*
X1095579Y-83887D01*
X1094487Y-82429D01*
X1094051Y-80388D01*
X1094706Y-78346D01*
X1096234Y-76887D01*
X1097981Y-76304D01*
X1099727Y-76887D01*
X1101256Y-78346D01*
X1101911Y-80388D01*
X1101474Y-82429D01*
X1100383Y-83887D01*
X1099073Y-84471D01*
X1096889D01*
X1094924Y-85346D01*
X1093614Y-87096D01*
X1093178Y-89137D01*
X1093614Y-91180D01*
X1094706Y-92638D01*
X1096453Y-93512D01*
X1097981Y-93804D01*
G01X1111551Y-94387D02*
X1119411Y-76304D01*
G01X1132981D02*
X1131234Y-76887D01*
X1129924Y-78346D01*
X1129051Y-80095D01*
X1128396Y-82429D01*
X1128178Y-85054D01*
X1128396Y-87679D01*
X1129051Y-90013D01*
X1129924Y-91763D01*
X1131234Y-93221D01*
X1132981Y-93804D01*
X1134727Y-93221D01*
X1136038Y-91763D01*
X1136911Y-90013D01*
X1137566Y-87679D01*
X1137784Y-85054D01*
X1137566Y-82429D01*
X1136911Y-80095D01*
X1136038Y-78346D01*
X1134727Y-76887D01*
X1132981Y-76304D01*
G01X1150044Y-93804D02*
X1150481Y-90013D01*
X1151136Y-86804D01*
X1152009Y-83887D01*
X1153101Y-80679D01*
X1154848Y-76304D01*
X1146114D01*
G01X1164051Y-94387D02*
X1171911Y-76304D01*
G01X1181333Y-79221D02*
X1182643Y-77471D01*
X1184171Y-76596D01*
X1185918Y-76304D01*
X1188101Y-76887D01*
X1189629Y-78346D01*
X1190066Y-80095D01*
X1189848Y-81846D01*
X1188974Y-83304D01*
X1184608Y-86221D01*
X1182643Y-88262D01*
X1181333Y-91180D01*
X1180896Y-93804D01*
X1190066D01*
G01X1202981Y-76304D02*
X1201234Y-76887D01*
X1199924Y-78346D01*
X1199051Y-80095D01*
X1198396Y-82429D01*
X1198178Y-85054D01*
X1198396Y-87679D01*
X1199051Y-90013D01*
X1199924Y-91763D01*
X1201234Y-93221D01*
X1202981Y-93804D01*
X1204727Y-93221D01*
X1206038Y-91763D01*
X1206911Y-90013D01*
X1207566Y-87679D01*
X1207784Y-85054D01*
X1207566Y-82429D01*
X1206911Y-80095D01*
X1206038Y-78346D01*
X1204727Y-76887D01*
X1202981Y-76304D01*
G01X1220481Y-93804D02*
Y-76304D01*
X1217861Y-79804D01*
G01Y-93804D02*
X1223101D01*
G01X1237544D02*
X1237981Y-90013D01*
X1238636Y-86804D01*
X1239509Y-83887D01*
X1240601Y-80679D01*
X1242348Y-76304D01*
X1233614D01*
G01X1128178Y-48804D02*
Y-31304D01*
X1132544D01*
X1134291Y-32179D01*
X1135601Y-33346D01*
X1136693Y-35095D01*
X1137566Y-37138D01*
X1137784Y-40054D01*
X1137566Y-42971D01*
X1136693Y-45013D01*
X1135601Y-46763D01*
X1134291Y-47929D01*
X1132544Y-48804D01*
X1128178D01*
G01X1154411D02*
Y-37138D01*
G01Y-39179D02*
X1153538Y-38013D01*
X1152227Y-37429D01*
X1150699Y-37138D01*
X1149171Y-37721D01*
X1147861Y-38887D01*
X1146987Y-40637D01*
X1146551Y-42971D01*
X1146987Y-45304D01*
X1147861Y-47054D01*
X1149171Y-48221D01*
X1150699Y-48804D01*
X1152227Y-48512D01*
X1153538Y-47638D01*
X1154411Y-46471D01*
G01X1167981Y-31304D02*
Y-48804D01*
G01X1164924Y-37138D02*
X1171038D01*
G01X1182206Y-40929D02*
X1189193D01*
X1188538Y-38887D01*
X1187446Y-37721D01*
X1185918Y-37138D01*
X1184389Y-37429D01*
X1183079Y-38304D01*
X1182206Y-40346D01*
X1181769Y-42096D01*
Y-43846D01*
X1182206Y-45596D01*
X1183298Y-47346D01*
X1184608Y-48512D01*
X1186136Y-48804D01*
X1187664Y-48221D01*
X1189193Y-46471D01*
G01X3937Y0D02*
X116260D01*
G01X0Y3937D02*
G03X3937Y0I3937J0D01*
G01X0Y723480D02*
Y3937D01*
G01X416Y725241D02*
G03X0Y723480I3521J-1761D01*
G01X18597Y761603D02*
X416Y725241D01*
G01X22118Y763780D02*
G03X18597Y761603I1J-3937D01*
G01X386149Y763780D02*
X22118D01*
G01X120197Y3937D02*
Y429331D01*
G01X116260Y0D02*
G03X120197Y3937I0J3937D01*
G01X128071D02*
G03X132008Y0I3937J0D01*
G01X128071Y43308D02*
G03X120197I-3937J0D01*
G01X132008Y0D02*
X275709D01*
G01X128071Y3937D02*
Y43308D01*
G01X120197Y74016D02*
G03X128071I3937J0D01*
G01D02*
Y425394D01*
G01X124134Y433268D02*
X283583D01*
G01X124134D02*
G03X120197Y429331I0J-3937D01*
G01X188504Y425394D02*
X128071D01*
G01X152497Y21054D02*
G03I-4291J0D01*
G01X188504Y425394D02*
G03Y433268I0J3937D01*
G01X275709Y0D02*
G03X279646Y3937I0J3937D01*
G01X287520Y43308D02*
G03X279646I-3937J0D01*
G01Y3937D02*
Y43308D01*
G01Y74016D02*
G03X287520I3937J0D01*
G01X279646D02*
Y425394D01*
G01X265438Y405580D02*
G03I-4291J0D01*
G01X287520Y429331D02*
G03X283583Y433268I-3937J0D01*
G01X219213D02*
G03Y425394I0J-3937D01*
G01X279646D02*
X219213D01*
G01X291457Y0D02*
X921260D01*
G01X287520Y3937D02*
G03X291457Y0I3937J0D01*
G01X287520Y429331D02*
Y3937D01*
G01X408268Y188976D02*
Y723480D01*
G01Y188976D02*
G03X412205I1968J0D01*
G01X564173D02*
X412205D01*
G01X416142Y348379D02*
Y196851D01*
G01D02*
X560237D01*
G01X416142Y348379D02*
G03X408268I-3937J0D01*
G01Y379088D02*
G03X416142I3937J0D01*
G01Y688303D02*
Y379088D01*
G01Y688303D02*
G03X408268I-3937J0D01*
G01X389671Y761603D02*
G03X386149Y763780I-3522J-1760D01*
G01X407852Y725241D02*
X389671Y761603D01*
G01X408268Y723480D02*
G03X407852Y725241I-3937J0D01*
G01X524242Y763780D02*
X403757D01*
G01D02*
G03X400235Y758082I0J-3937D01*
G01X408268Y719012D02*
G03X416142I3937J0D01*
G01Y723480D02*
G03X414895Y728763I-11811J1D01*
G01X400235Y758082D02*
X414895Y728763D01*
G01X416142Y723480D02*
Y719012D01*
G01X490789Y356293D02*
G03I-4291J0D01*
G01X564173Y188976D02*
G03X568110I1968J0D01*
G01Y589622D02*
Y188976D01*
G01X560237Y261975D02*
Y196851D01*
G01X568111Y261975D02*
G03X560237I-3937J0D01*
G01Y292684D02*
G03X568111I3937J0D01*
G01X560237Y551040D02*
Y292684D01*
G01X568111Y551040D02*
G03X560237I-3937J0D01*
G01X568526Y591382D02*
G03X568110Y589622I3521J-1761D01*
G01X586707Y627745D02*
X568526Y591382D01*
G01X560237Y581748D02*
G03X568111I3937J0D01*
G01X561484Y594905D02*
G03X560237Y589622I10564J-5282D01*
G01D02*
Y581748D01*
G01X579665Y631267D02*
X561484Y594904D01*
G01X524242Y763780D02*
G03X532116I3937J0D01*
G01X834646D02*
X532116D01*
G01X590228Y629921D02*
G03X586707Y627745I0J-3937D01*
G01X842520Y629921D02*
X590228D01*
G01X590229Y637796D02*
G03X579665Y631268I0J-11812D01*
G01X590229Y637796D02*
X838583D01*
G01X842520Y629921D02*
G03X846457Y633858I0J3937D01*
G01Y759843D02*
Y633858D01*
G01X838583Y637796D02*
Y709449D01*
G01X850394Y763780D02*
G03X846457Y759843I0J-3937D01*
G01X903079Y763780D02*
X850394D01*
G01X812123Y734367D02*
G03I-4292J0D01*
G01X838583Y759843D02*
G03X834646Y763780I-3937J0D01*
G01X838583Y740158D02*
G03X846457I3937J0D01*
G01Y709449D02*
G03X838583I-3937J0D01*
G01Y740158D02*
Y759843D01*
G01X921260Y0D02*
G03X925197Y3937I0J3937D01*
G01D02*
Y723480D01*
G01X906600Y761603D02*
G03X903079Y763780I-3522J-1760D01*
G01X924781Y725241D02*
X906600Y761603D01*
G01X925197Y723480D02*
G03X924781Y725241I-3937J0D01*
G54D11*
X38500Y53200D03*
X48200Y678984D03*
X78268Y63455D03*
X104000Y482200D03*
X108500Y490700D03*
X104000D03*
X108277Y574051D03*
X86028Y693139D03*
X81928Y693239D03*
X111200Y713300D03*
X174588Y493113D03*
X187167Y506384D03*
X198700Y520300D03*
X203500D03*
X212600Y520400D03*
X141914Y523238D03*
X182648Y506454D03*
X142572Y637132D03*
X150872D03*
X166500Y637200D03*
X157458Y637232D03*
X145279Y622570D03*
X172700Y626100D03*
X176800D03*
X180985D03*
X185085D03*
X189185D03*
X193285D03*
X149400Y626600D03*
X204100Y641400D03*
X154300Y706915D03*
X168047Y708475D03*
X151749Y699115D03*
X164249D03*
X210123Y658996D03*
X267514Y543985D03*
X243700Y555500D03*
X229342Y518355D03*
X238000Y625200D03*
X234000D03*
X221900Y627100D03*
X229952Y629830D03*
X225900Y627100D03*
X251900Y616800D03*
X243900D03*
X262823Y628096D03*
X236000Y642600D03*
X223400Y641400D03*
X225984Y662443D03*
X258431Y708224D03*
X246700Y679300D03*
X247500Y705700D03*
X214723Y655496D03*
X343582Y181878D03*
X347882Y274478D03*
X346819Y524075D03*
X350400Y531900D03*
X341226Y531909D03*
X334827Y520553D03*
X304617Y593281D03*
X299000Y661500D03*
X289612Y664929D03*
X291700Y733600D03*
X287620Y733620D03*
X374883Y184553D03*
X359481Y487866D03*
X384300Y551800D03*
X361120Y589086D03*
X374600Y586800D03*
X464342Y57258D03*
X443489Y45801D03*
X468400Y64700D03*
X472700Y64600D03*
X594541Y32981D03*
X590347Y60707D03*
X703300Y25200D03*
X713200Y394200D03*
X712851Y478282D03*
X712000Y438800D03*
X718300Y394200D03*
X725200Y438800D03*
X754800Y530400D03*
X854596Y162535D03*
X841625Y181177D03*
X846077Y155624D03*
X838627Y382215D03*
X846456Y357457D03*
X834984Y374469D03*
X796100Y393200D03*
X801200D03*
X811099Y477179D03*
X794900Y437800D03*
X808100D03*
G54D20*
X40806Y543876D03*
X33358Y543881D03*
X40787Y555153D03*
X33287D03*
X40600Y549500D03*
X33100D03*
X40806Y538249D03*
X33258Y538254D03*
X40706Y532622D03*
X61346Y647850D03*
X127000Y534600D03*
X136900Y529700D03*
X127000Y530300D03*
X137067Y537795D03*
X118403Y613818D03*
X123300Y599000D03*
X179039Y474031D03*
X208700Y495300D03*
X146292Y519686D03*
Y515686D03*
X199900Y503300D03*
X188128Y643963D03*
X145149Y683715D03*
X155149Y711215D03*
X268000Y474380D03*
X281045Y561694D03*
X247996Y557061D03*
X248077Y563068D03*
X264000Y553100D03*
X272425Y541121D03*
X239596Y560398D03*
Y564498D03*
X283500Y527300D03*
X283600Y522800D03*
Y535000D03*
X239900Y601000D03*
X240300Y589800D03*
X232700Y634300D03*
X248700Y578300D03*
X247700Y585700D03*
X248600Y573500D03*
X250725Y567260D03*
X268719Y574462D03*
X259576Y669731D03*
X282670Y647978D03*
X235489Y662667D03*
X282670Y652044D03*
X272020Y719420D03*
X347782Y193578D03*
X348082Y178678D03*
Y257778D03*
X340318Y232181D03*
X345100Y543800D03*
X347861Y507831D03*
X303053Y620550D03*
X296315Y592831D03*
X311244Y582263D03*
X344666Y594759D03*
X340800Y585500D03*
X291382Y691947D03*
X342200Y672000D03*
X367280Y245508D03*
X362481Y225861D03*
X367280Y241308D03*
X364261Y475491D03*
X359602Y480368D03*
X385800Y533400D03*
X386400Y564400D03*
X362664Y635920D03*
X387800Y613900D03*
X389600Y597200D03*
X389181Y622265D03*
X489800Y42000D03*
X490200Y34000D03*
X479526Y59562D03*
X485814Y51841D03*
X586020Y50435D03*
X650346Y521683D03*
X650383Y530195D03*
X653678Y517560D03*
X733800Y426800D03*
X846611Y165178D03*
X848968Y207864D03*
Y211864D03*
X846056Y344740D03*
X845460Y403998D03*
Y395998D03*
Y399998D03*
X816700Y425800D03*
G54D104*
X724200Y398380D03*
X807100Y397380D03*
G54D105*
X869622Y191265D03*
X866114Y383399D03*
G54D12*
X55300Y45000D03*
X33265Y532638D03*
X61454Y639950D03*
X39754Y679750D03*
X95068Y55255D03*
X133277Y613060D03*
X131262Y603311D03*
X134249Y599062D03*
X132295Y617354D03*
X114271Y596454D03*
X106249Y599764D03*
Y607964D03*
Y603864D03*
Y612064D03*
Y624364D03*
Y620264D03*
X109899Y701465D03*
X137649Y687715D03*
X179063Y459780D03*
Y469880D03*
X268000Y470300D03*
Y458200D03*
X268400Y489500D03*
X237863Y539142D03*
X245428Y536660D03*
X215800Y512066D03*
X243238Y528501D03*
X235709Y524700D03*
X235600Y520563D03*
X267700Y605800D03*
X238858Y581690D03*
X240200Y585700D03*
X241142Y572585D03*
X238625Y568522D03*
X253560Y593575D03*
X256882Y642199D03*
X274700Y644572D03*
X265800Y639500D03*
X271990Y723570D03*
X340348Y228017D03*
X347961Y251004D03*
Y247004D03*
X347962Y242193D03*
X344482Y265778D03*
X289600Y551300D03*
X289355Y546706D03*
X347800Y511900D03*
Y500200D03*
X334804Y559544D03*
X334864Y555473D03*
X334795Y563788D03*
X323800Y526000D03*
X302000Y616384D03*
X344300Y581000D03*
X334755Y567922D03*
X334799Y572721D03*
X332553Y576849D03*
X321475Y678443D03*
X291318Y684153D03*
X334723Y677472D03*
X320083Y674407D03*
X389536Y585080D03*
X389200Y637900D03*
X389500Y589100D03*
X389236Y628580D03*
X389600Y605400D03*
X387836Y617980D03*
X389500Y593200D03*
X389600Y601300D03*
X388195Y568431D03*
X388244Y572999D03*
X386102Y694223D03*
X385400Y683900D03*
X385300Y679800D03*
Y675600D03*
X434185Y38057D03*
X442585Y21957D03*
X435858Y56153D03*
X442685Y30457D03*
Y26157D03*
X442616Y38147D03*
X489800Y30000D03*
X489700Y21800D03*
X489800Y26000D03*
X527600Y54648D03*
X527597Y50148D03*
X618596Y55138D03*
X581904Y41467D03*
X579347Y37207D03*
X650383Y525811D03*
X733800Y431000D03*
X851222Y149514D03*
X846611Y169478D03*
X848968Y203864D03*
Y215964D03*
X836239Y356008D03*
X836213Y360311D03*
X836216Y351914D03*
X816700Y430000D03*
X863630Y215262D03*
G54D30*
X108500Y482200D03*
X101113Y522777D03*
X101100Y515300D03*
X81032Y517477D03*
X81068Y509866D03*
X69778Y517477D03*
X69900Y510000D03*
X75405Y517477D03*
X75373Y509879D03*
X86673Y510000D03*
X92000Y517400D03*
X86659Y517477D03*
X93531Y496341D03*
X119600Y628800D03*
X117349Y697047D03*
X121449Y694247D03*
X113349Y697047D03*
X184924Y493148D03*
X157896Y519319D03*
X161902Y519349D03*
X142000Y515500D03*
X186537Y519381D03*
X182474Y520691D03*
X166280Y520400D03*
X170380D03*
X191400Y505800D03*
X194649Y520351D03*
X190600Y519400D03*
X178469Y521393D03*
X195500Y506200D03*
X174400Y516100D03*
X212000Y502700D03*
X186976Y636468D03*
X191076Y636598D03*
X170600Y637200D03*
X174700D03*
X178776Y636468D03*
X182876D03*
X153700Y626200D03*
X155849Y699115D03*
X211706Y641392D03*
X158349Y706915D03*
X225262Y518580D03*
X258969Y544921D03*
X247900Y616800D03*
X258000Y649664D03*
X232000Y642600D03*
X219200Y642200D03*
X271200Y676100D03*
X250800Y679300D03*
X262645Y708235D03*
X258500Y679200D03*
X238807Y658571D03*
X342497Y524061D03*
X345100Y539600D03*
X324500Y537200D03*
X320000D03*
X352480Y587564D03*
X286703Y618411D03*
X347680Y639664D03*
X387458Y74149D03*
X391458D03*
X360382Y193600D03*
X388489Y555935D03*
X378800Y583800D03*
X383000D03*
X356680Y589064D03*
X443457Y53415D03*
X594504Y60667D03*
X636647Y60307D03*
X723800Y33100D03*
Y25400D03*
X720017Y478614D03*
X716100Y438800D03*
X721100D03*
X842168Y188614D03*
X858622Y162514D03*
X850730Y357478D03*
X853060Y407698D03*
X823728Y477000D03*
X804000Y437800D03*
X799000D03*
G54D21*
X66278Y540794D03*
Y543943D03*
Y537644D03*
Y547093D03*
Y550242D03*
Y553392D03*
Y556542D03*
Y559691D03*
Y562841D03*
Y565990D03*
Y578589D03*
Y581738D03*
Y584888D03*
Y569140D03*
Y572290D03*
Y575439D03*
X85175Y547093D03*
X91474Y540794D03*
X88325D03*
X85175D03*
X91474Y543943D03*
X88325D03*
X85175D03*
X91474Y537644D03*
X88325D03*
X85175D03*
X72577Y540794D03*
X69427D03*
X72577Y543943D03*
X69427D03*
X72577Y537644D03*
X69427D03*
X91474Y547093D03*
X88325D03*
X72577D03*
X69427D03*
X91474Y550242D03*
X88325D03*
X85175D03*
X72577D03*
X69427D03*
X91474Y553392D03*
X88325D03*
X85175D03*
X72577D03*
X69427D03*
X91474Y556542D03*
X88325D03*
X85175D03*
X72577D03*
X69427D03*
X91474Y559691D03*
X88325D03*
X85175D03*
X72577D03*
X69427D03*
X91474Y562841D03*
X88325D03*
X85175D03*
X72577D03*
X69427D03*
X91474Y565990D03*
X88325D03*
X85175D03*
X72577D03*
X69427D03*
X91474Y569140D03*
Y572290D03*
Y575439D03*
Y578589D03*
Y581738D03*
Y584888D03*
X88325Y578589D03*
X85175D03*
X88325Y581738D03*
X85175D03*
X88325Y584888D03*
X85175D03*
X72577Y578589D03*
X69427D03*
X72577Y581738D03*
X69427D03*
X72577Y584888D03*
X69427D03*
X88325Y569140D03*
X85175D03*
X72577D03*
X69427D03*
X88325Y572290D03*
X85175D03*
X72577D03*
X69427D03*
X88325Y575439D03*
X85175D03*
X72577D03*
X69427D03*
X154724Y547244D03*
Y550394D03*
Y553543D03*
Y556693D03*
Y559842D03*
Y562992D03*
X157874Y547244D03*
Y550394D03*
Y553543D03*
Y556693D03*
Y559842D03*
Y562992D03*
X161023Y547244D03*
Y550394D03*
Y553543D03*
Y556693D03*
Y559842D03*
Y562992D03*
X164173Y537795D03*
Y540945D03*
Y544094D03*
Y547244D03*
Y550394D03*
Y553543D03*
Y556693D03*
Y559842D03*
Y562992D03*
X167323Y537795D03*
Y540945D03*
Y544094D03*
Y547244D03*
Y550394D03*
Y553543D03*
Y556693D03*
Y559842D03*
Y562992D03*
X170472Y537795D03*
Y540945D03*
Y544094D03*
Y547244D03*
Y550394D03*
Y553543D03*
Y556693D03*
Y559842D03*
Y562992D03*
X173622Y537795D03*
Y540945D03*
Y544094D03*
Y547244D03*
Y550394D03*
Y553543D03*
Y556693D03*
Y559842D03*
Y562992D03*
X176771Y537795D03*
Y540945D03*
Y544094D03*
Y547244D03*
Y550394D03*
Y553543D03*
Y556693D03*
X179921Y537795D03*
Y540945D03*
Y544094D03*
Y547244D03*
Y550394D03*
Y553543D03*
Y556693D03*
Y562992D03*
X183071Y537795D03*
Y540945D03*
Y544094D03*
Y547244D03*
Y550394D03*
Y553543D03*
Y556693D03*
Y562992D03*
X186220Y537795D03*
Y540945D03*
Y544094D03*
Y547244D03*
Y550394D03*
Y553543D03*
Y556693D03*
Y562992D03*
X189370Y537795D03*
Y540945D03*
Y544094D03*
Y547244D03*
Y550394D03*
Y553543D03*
Y556693D03*
Y562992D03*
X192519Y537795D03*
Y540945D03*
Y544094D03*
Y547244D03*
Y550394D03*
Y553543D03*
Y556693D03*
Y562992D03*
X195669Y537795D03*
Y540945D03*
Y544094D03*
Y547244D03*
Y550394D03*
Y553543D03*
Y556693D03*
Y562992D03*
X198819Y537795D03*
Y540945D03*
Y544094D03*
Y547244D03*
Y550394D03*
Y553543D03*
Y556693D03*
X201968Y537795D03*
Y540945D03*
Y544094D03*
Y547244D03*
Y550394D03*
Y553543D03*
Y556693D03*
Y559842D03*
Y562992D03*
X205118Y537795D03*
Y540945D03*
Y544094D03*
Y547244D03*
Y550394D03*
Y553543D03*
Y556693D03*
Y559842D03*
Y562992D03*
X208267Y537795D03*
Y540945D03*
Y544094D03*
Y547244D03*
Y550394D03*
Y553543D03*
Y556693D03*
Y559842D03*
Y562992D03*
X211417Y537795D03*
Y540945D03*
Y544094D03*
Y547244D03*
Y550394D03*
Y553543D03*
Y556693D03*
Y559842D03*
Y562992D03*
X154724Y566142D03*
Y569291D03*
Y572441D03*
Y575590D03*
Y578740D03*
Y581890D03*
Y585039D03*
Y588189D03*
Y591338D03*
Y594488D03*
X157874Y566142D03*
Y569291D03*
Y572441D03*
Y575590D03*
Y578740D03*
Y581890D03*
Y585039D03*
Y588189D03*
Y591338D03*
Y594488D03*
X161023Y566142D03*
Y569291D03*
Y572441D03*
Y575590D03*
Y578740D03*
Y581890D03*
Y585039D03*
Y588189D03*
Y591338D03*
Y594488D03*
X164173Y566142D03*
Y569291D03*
Y572441D03*
Y575590D03*
Y578740D03*
Y581890D03*
Y585039D03*
Y588189D03*
Y591338D03*
Y594488D03*
Y597638D03*
Y600787D03*
Y603937D03*
X167323Y566142D03*
Y569291D03*
Y572441D03*
Y575590D03*
Y578740D03*
Y581890D03*
Y585039D03*
Y588189D03*
Y591338D03*
Y594488D03*
Y597638D03*
Y600787D03*
Y603937D03*
X170472Y566142D03*
Y569291D03*
Y572441D03*
Y575590D03*
Y578740D03*
Y581890D03*
Y585039D03*
Y588189D03*
Y591338D03*
Y594488D03*
Y597638D03*
Y600787D03*
Y603937D03*
X173622Y566142D03*
Y569291D03*
Y572441D03*
Y575590D03*
Y578740D03*
Y581890D03*
Y585039D03*
Y588189D03*
Y591338D03*
Y594488D03*
Y597638D03*
Y600787D03*
Y603937D03*
X176771Y585039D03*
Y588189D03*
Y591338D03*
Y594488D03*
Y597638D03*
Y600787D03*
Y603937D03*
X179921Y566142D03*
Y569291D03*
Y572441D03*
Y575590D03*
Y578740D03*
Y585039D03*
Y588189D03*
Y591338D03*
Y594488D03*
Y597638D03*
Y600787D03*
Y603937D03*
X183071Y566142D03*
Y569291D03*
Y572441D03*
Y575590D03*
Y578740D03*
Y585039D03*
Y588189D03*
Y591338D03*
Y594488D03*
Y597638D03*
Y600787D03*
Y603937D03*
X186220Y566142D03*
Y569291D03*
Y572441D03*
Y575590D03*
Y578740D03*
Y585039D03*
Y588189D03*
Y591338D03*
Y594488D03*
Y597638D03*
Y600787D03*
Y603937D03*
X189370Y566142D03*
Y569291D03*
Y572441D03*
Y575590D03*
Y578740D03*
Y585039D03*
Y588189D03*
Y591338D03*
Y594488D03*
Y597638D03*
Y600787D03*
Y603937D03*
X192519Y566142D03*
Y569291D03*
Y572441D03*
Y575590D03*
Y578740D03*
Y585039D03*
Y588189D03*
Y591338D03*
Y594488D03*
Y597638D03*
Y600787D03*
Y603937D03*
X195669Y566142D03*
Y569291D03*
Y572441D03*
Y575590D03*
Y578740D03*
Y585039D03*
Y588189D03*
Y591338D03*
Y594488D03*
Y597638D03*
Y600787D03*
Y603937D03*
X198819Y585039D03*
Y588189D03*
Y591338D03*
Y594488D03*
Y597638D03*
Y600787D03*
Y603937D03*
X201968Y566142D03*
Y569291D03*
Y572441D03*
Y575590D03*
Y578740D03*
Y581890D03*
Y585039D03*
Y588189D03*
Y591338D03*
Y594488D03*
Y597638D03*
Y600787D03*
Y603937D03*
X205118Y566142D03*
Y569291D03*
Y572441D03*
Y575590D03*
Y578740D03*
Y581890D03*
Y585039D03*
Y588189D03*
Y591338D03*
Y594488D03*
Y597638D03*
Y600787D03*
Y603937D03*
X208267Y566142D03*
Y569291D03*
Y572441D03*
Y575590D03*
Y578740D03*
Y581890D03*
Y585039D03*
Y588189D03*
Y591338D03*
Y594488D03*
Y597638D03*
Y600787D03*
Y603937D03*
X211417Y566142D03*
Y569291D03*
Y572441D03*
Y575590D03*
Y578740D03*
Y581890D03*
Y585039D03*
Y588189D03*
Y591338D03*
Y594488D03*
Y597638D03*
Y600787D03*
Y603937D03*
X214567Y547244D03*
Y550394D03*
Y553543D03*
Y556693D03*
Y559842D03*
Y562992D03*
X217716Y547244D03*
Y550394D03*
Y553543D03*
Y556693D03*
Y559842D03*
Y562992D03*
X220866Y547244D03*
Y550394D03*
Y553543D03*
Y556693D03*
Y559842D03*
Y562992D03*
X214567Y566142D03*
Y569291D03*
Y572441D03*
Y575590D03*
Y578740D03*
Y581890D03*
Y585039D03*
Y588189D03*
Y591338D03*
Y594488D03*
X217716Y566142D03*
Y569291D03*
Y572441D03*
Y575590D03*
Y578740D03*
Y581890D03*
Y585039D03*
Y588189D03*
Y591338D03*
Y594488D03*
X220866Y566142D03*
Y569291D03*
Y572441D03*
Y575590D03*
Y578740D03*
Y581890D03*
Y585039D03*
Y588189D03*
Y591338D03*
Y594488D03*
G54D13*
X58700Y45000D03*
X36665Y532638D03*
X64854Y639950D03*
X43154Y679750D03*
X98468Y55255D03*
X136677Y613060D03*
X134662Y603311D03*
X137649Y599062D03*
X135695Y617354D03*
X117671Y596454D03*
X109649Y599764D03*
Y607964D03*
Y603864D03*
Y612064D03*
Y624364D03*
Y620264D03*
X113299Y701465D03*
X141049Y687715D03*
X182463Y459780D03*
Y469880D03*
X271400Y470300D03*
Y458200D03*
X271800Y489500D03*
X241263Y539142D03*
X248828Y536660D03*
X219200Y512066D03*
X246638Y528501D03*
X239109Y524700D03*
X239000Y520563D03*
X271100Y605800D03*
X242258Y581690D03*
X243600Y585700D03*
X244542Y572585D03*
X242025Y568522D03*
X256960Y593575D03*
X260282Y642199D03*
X278100Y644572D03*
X269200Y639500D03*
X275390Y723570D03*
X343748Y228017D03*
X351361Y251004D03*
Y247004D03*
X351362Y242193D03*
X347882Y265778D03*
X293000Y551300D03*
X292755Y546706D03*
X351200Y511900D03*
Y500200D03*
X338204Y559544D03*
X338264Y555473D03*
X338195Y563788D03*
X327200Y526000D03*
X305400Y616384D03*
X347700Y581000D03*
X338155Y567922D03*
X338199Y572721D03*
X335953Y576849D03*
X324875Y678443D03*
X294718Y684153D03*
X338123Y677472D03*
X323483Y674407D03*
X392936Y585080D03*
X392600Y637900D03*
X392900Y589100D03*
X392636Y628580D03*
X393000Y605400D03*
X391236Y617980D03*
X392900Y593200D03*
X393000Y601300D03*
X391595Y568431D03*
X391644Y572999D03*
X389502Y694223D03*
X388800Y683900D03*
X388700Y679800D03*
Y675600D03*
X437585Y38057D03*
X445985Y21957D03*
X439258Y56153D03*
X446085Y30457D03*
Y26157D03*
X446016Y38147D03*
X493200Y30000D03*
X493100Y21800D03*
X493200Y26000D03*
X531000Y54648D03*
X530997Y50148D03*
X621996Y55138D03*
X585304Y41467D03*
X582747Y37207D03*
X653783Y525811D03*
X737200Y431000D03*
X854622Y149514D03*
X850011Y169478D03*
X852368Y203864D03*
Y215964D03*
X839639Y356008D03*
X839613Y360311D03*
X839616Y351914D03*
X820100Y430000D03*
X867030Y215262D03*
G54D31*
X108500Y478800D03*
X93531Y492941D03*
X101113Y519377D03*
X101100Y511900D03*
X81032Y514077D03*
X81068Y506466D03*
X69778Y514077D03*
X69900Y506600D03*
X75405Y514077D03*
X75373Y506479D03*
X86673Y506600D03*
X92000Y514000D03*
X86659Y514077D03*
X119600Y625400D03*
X117349Y693647D03*
X121449Y690847D03*
X113349Y693647D03*
X184924Y489748D03*
X157896Y515919D03*
X161902Y515949D03*
X142000Y512100D03*
X186537Y515981D03*
X182474Y517291D03*
X166280Y517000D03*
X170380D03*
X191400Y502400D03*
X194649Y516951D03*
X190600Y516000D03*
X178469Y517993D03*
X195500Y502800D03*
X174400Y512700D03*
X212000Y499300D03*
X211706Y637992D03*
X186976Y633068D03*
X191076Y633198D03*
X170600Y633800D03*
X174700D03*
X178776Y633068D03*
X182876D03*
X153700Y622800D03*
X155849Y695715D03*
X158349Y703515D03*
X225262Y515180D03*
X258969Y541521D03*
X247900Y613400D03*
X258000Y646264D03*
X232000Y639200D03*
X219200Y638800D03*
X271200Y672700D03*
X250800Y675900D03*
X262645Y704835D03*
X258500Y675800D03*
X238807Y655171D03*
X342497Y520661D03*
X345100Y536200D03*
X324500Y533800D03*
X320000D03*
X347680Y636264D03*
X352480Y584164D03*
X286703Y615011D03*
X387458Y70749D03*
X391458D03*
X360382Y190200D03*
X388489Y552535D03*
X378800Y580400D03*
X383000D03*
X356680Y585664D03*
X443457Y50015D03*
X594504Y57267D03*
X636647Y56907D03*
X723800Y29700D03*
Y22000D03*
X720017Y475214D03*
X716100Y435400D03*
X721100D03*
X842168Y185214D03*
X858622Y159114D03*
X850730Y354078D03*
X853060Y404298D03*
X823728Y473600D03*
X804000Y434400D03*
X799000D03*
G54D40*
X131900Y624300D03*
X340034Y112312D03*
X345034D03*
X370220Y580786D03*
X509055Y22402D03*
X504381Y22399D03*
X631781Y57411D03*
G54D22*
X56844Y588651D03*
X28971Y675883D03*
X43800Y675800D03*
X55895Y643491D03*
X49500Y659909D03*
X130500Y599000D03*
X128800Y611100D03*
X140800Y616400D03*
X88266Y621165D03*
X127263Y594662D03*
X138473Y603273D03*
X128800Y694400D03*
X118477Y702077D03*
X122100Y698500D03*
X112850Y641488D03*
X112403Y656627D03*
X77903Y689785D03*
X73265Y647355D03*
X83450Y646620D03*
X139000Y740015D03*
X104132Y722843D03*
X199000Y479500D03*
X196100Y524600D03*
X200300Y525500D03*
X188158Y527500D03*
X192800Y529100D03*
X179021Y528902D03*
X173175Y528444D03*
X169420Y526499D03*
X183350Y527900D03*
X165572Y529088D03*
X154151Y523478D03*
X160743Y527786D03*
X153985Y527761D03*
X144800Y549100D03*
X204979Y525545D03*
X213050Y525000D03*
X204843Y623300D03*
X200000Y618900D03*
X212750Y618700D03*
X191435Y614794D03*
X187221Y617507D03*
X182819Y617616D03*
X176993Y613763D03*
X175300Y618200D03*
X172048Y614508D03*
X161958Y633782D03*
X143221Y611975D03*
X149800Y618700D03*
X147262Y615302D03*
X144993Y626564D03*
X142500Y599062D03*
X155378Y618114D03*
X210800Y622500D03*
X157450Y626650D03*
X193000Y648700D03*
X160200Y699165D03*
X143100Y696800D03*
X144048Y735514D03*
X276995Y558100D03*
X230838Y566081D03*
X235484Y561538D03*
X266700Y548600D03*
X250901Y531106D03*
X258969Y537520D03*
X221014Y526000D03*
X237344Y513444D03*
X233900Y516000D03*
X271966Y565966D03*
X266325Y557905D03*
X228541Y529541D03*
X243950Y522900D03*
X231800Y538900D03*
X229762Y522829D03*
X219800Y517100D03*
X242449Y532550D03*
X254560Y548551D03*
X253202Y544298D03*
X223593Y634091D03*
X234797Y568900D03*
X236421Y574788D03*
X235310Y585700D03*
X234034Y578517D03*
X246433Y567987D03*
X260131Y574893D03*
X217600Y620700D03*
X226300Y618800D03*
X237800Y629800D03*
X250087Y591300D03*
X236056Y596885D03*
X238700Y617900D03*
X255935Y583784D03*
X242866Y577122D03*
X261455Y579009D03*
X239963Y613061D03*
X260500Y637500D03*
X261025Y593260D03*
X239000Y687300D03*
X257000Y698900D03*
X281602Y657563D03*
X258400Y662000D03*
X279920Y703460D03*
X252400Y705750D03*
X262335Y653750D03*
X239842Y681600D03*
X252700Y643400D03*
X270100Y662700D03*
X222306Y737851D03*
X221987Y728528D03*
X279900Y715400D03*
X261305Y715957D03*
X339900Y123700D03*
X343292Y187765D03*
X338955Y179994D03*
X342228Y247493D03*
X341105Y237114D03*
X340000Y262678D03*
X343582Y271028D03*
X339387Y241609D03*
X350900Y485348D03*
X353700Y480668D03*
X350300Y443500D03*
X356502Y474400D03*
X338963Y440163D03*
X347800Y440100D03*
X288100Y542900D03*
X288883Y555249D03*
X349600Y539100D03*
X345864Y531341D03*
X351500Y524125D03*
X313791Y550221D03*
X330100Y559544D03*
X309592Y550099D03*
X327900Y555900D03*
X330188Y563900D03*
X322800Y549300D03*
X320700Y543250D03*
X336800Y545700D03*
X349422Y553098D03*
X348597Y548003D03*
X336800Y510000D03*
X297999Y550096D03*
X322000Y520700D03*
X341596Y500750D03*
X290889Y530299D03*
X316000Y530000D03*
X290889Y525299D03*
Y535299D03*
X316000Y536000D03*
X351300Y504000D03*
X298613Y597750D03*
X347451Y576772D03*
X349373Y571300D03*
X346577Y567339D03*
X327874Y576249D03*
X342300Y571800D03*
X328200D03*
X330200Y568100D03*
X303166Y599583D03*
X298500Y622200D03*
X316500Y618500D03*
X288771Y637726D03*
X344616Y590187D03*
X320937Y582655D03*
X306766Y582469D03*
X339304Y709335D03*
X285773Y657061D03*
X294018Y655000D03*
X290500Y644700D03*
X286007Y692279D03*
X310000Y690500D03*
X345977Y684410D03*
X345671Y680190D03*
X303279Y670477D03*
X328723Y674658D03*
X334673Y672886D03*
X287600Y726400D03*
X418487Y71447D03*
X366300Y190000D03*
X374890Y177173D03*
X369882Y225923D03*
X358050Y254056D03*
X362349Y255239D03*
X357846Y260273D03*
X363100Y220900D03*
X382500Y339800D03*
X382800Y353300D03*
X392800Y491900D03*
X376544Y460678D03*
X364275Y486275D03*
X386000Y485700D03*
X397388Y479012D03*
X383600Y473500D03*
X380113Y480400D03*
X391129Y448629D03*
X372300Y478900D03*
X367552Y480084D03*
X385600Y537300D03*
X387517Y560556D03*
X391700Y507300D03*
X386400Y609500D03*
X357200Y592900D03*
X374522Y591597D03*
X383500Y588800D03*
X383400Y598800D03*
X379100Y588400D03*
X384025Y594525D03*
X383500Y604900D03*
X388700Y633400D03*
X384200Y626000D03*
X384495Y569100D03*
X383944Y573339D03*
X364900Y581500D03*
X380700Y684096D03*
X380800Y679800D03*
Y675600D03*
X381593Y694069D03*
X497137Y42455D03*
X450900Y29000D03*
Y24000D03*
X474400Y56600D03*
X468800Y57000D03*
X485585Y34890D03*
X451231Y41843D03*
X450832Y50121D03*
X485300Y27500D03*
X453400Y19100D03*
X477171Y51517D03*
X483347Y63650D03*
X493238Y52126D03*
X450200Y34416D03*
X448226Y45257D03*
X460442Y53761D03*
X484513Y22548D03*
X481353Y18104D03*
X498100Y34000D03*
X477129Y66151D03*
X460800Y66850D03*
X519493Y50899D03*
X519517Y55714D03*
X524672Y18026D03*
X515337Y20945D03*
X556300Y47148D03*
X545000Y63300D03*
X622364Y24999D03*
X618546Y50576D03*
X582232Y60757D03*
X598656Y30307D03*
X593347Y43217D03*
X621691Y40136D03*
X626700Y60200D03*
X598513Y57106D03*
X593247Y47907D03*
X593563Y24910D03*
X604047Y57707D03*
X609247Y63207D03*
X673140Y41600D03*
X695544Y21750D03*
X703300Y30100D03*
X697305Y28963D03*
X713200Y399200D03*
X712851Y483089D03*
X678474Y478005D03*
X710633Y463904D03*
X644559Y528060D03*
X729900Y26900D03*
X774200Y37200D03*
X781100Y19400D03*
X731437Y21928D03*
X718200Y399200D03*
X716100Y430500D03*
X721100D03*
X728900Y426800D03*
X720017Y483158D03*
X734761Y470838D03*
X852682Y74813D03*
X858373Y174835D03*
X842508Y145014D03*
X856468Y207064D03*
X853750Y181603D03*
X837195Y177710D03*
X856196Y212359D03*
X838169Y337936D03*
X801100Y398200D03*
X796100D03*
X845111Y362071D03*
X857706Y399786D03*
X852716Y399376D03*
X847820Y375672D03*
X830809Y371019D03*
X799000Y429500D03*
X804000D03*
X811800Y425800D03*
X811099Y481767D03*
X823728Y481512D03*
X903755Y100137D03*
X887928Y177932D03*
X894711Y187059D03*
X871261Y218621D03*
X882745Y369882D03*
X890963Y375283D03*
G54D106*
X848918Y192564D03*
G54D14*
X34000Y54300D03*
X73768Y64555D03*
X93614Y507152D03*
X73427Y695585D03*
X127300Y643300D03*
X115619Y712795D03*
X283032Y736236D03*
X345034Y128412D03*
X294018Y665582D03*
X352180Y642014D03*
X539108Y74841D03*
X577404Y60567D03*
X641347Y63007D03*
X598947Y69007D03*
X603747Y67707D03*
X832572Y177477D03*
G54D32*
X124290Y490300D03*
Y485300D03*
Y480300D03*
Y475300D03*
Y470300D03*
Y465300D03*
Y460300D03*
Y495300D03*
X161440Y460300D03*
Y465300D03*
Y470300D03*
Y475300D03*
Y480300D03*
Y485300D03*
Y490300D03*
Y495300D03*
X258375Y460300D03*
Y465300D03*
Y470300D03*
Y475300D03*
Y480300D03*
Y485300D03*
Y490300D03*
X221225D03*
Y485300D03*
Y480300D03*
Y475300D03*
Y470300D03*
Y465300D03*
Y460300D03*
X258375Y495300D03*
X221225D03*
X267600Y582000D03*
Y587000D03*
Y592000D03*
Y597000D03*
X287600D03*
Y592000D03*
Y587000D03*
Y582000D03*
X379088Y537881D03*
Y532881D03*
Y527881D03*
Y522881D03*
X359088D03*
Y527881D03*
Y532881D03*
Y537881D03*
G54D107*
X851618Y192564D03*
G54D41*
X131900Y629900D03*
X340034Y117912D03*
X345034D03*
X370220Y586386D03*
X509055Y28002D03*
X504381Y27999D03*
X631781Y63011D03*
G54D23*
X41452Y659909D03*
X179037Y463761D03*
X208200Y626900D03*
X145049Y687715D03*
X268300Y465400D03*
X254958Y589579D03*
X281370Y637250D03*
X246925Y633776D03*
X272203Y704337D03*
X274600Y640772D03*
X259500Y666000D03*
X347682Y189778D03*
X290095Y539294D03*
X316000Y526100D03*
X328200Y581394D03*
Y585000D03*
X385500Y541100D03*
X387411Y577031D03*
X366614Y639820D03*
X382500Y698000D03*
X375900Y710400D03*
X479426Y55778D03*
X489700Y38000D03*
X468786Y53022D03*
X549200Y61200D03*
X614247Y63107D03*
G54D50*
X174749Y691815D03*
X363482Y185174D03*
X456088Y54522D03*
X438855Y47144D03*
X438857Y42488D03*
X438846Y51800D03*
X584904Y45967D03*
X609047Y30307D03*
X787000Y29800D03*
X845922Y160314D03*
X854222Y145014D03*
X850306Y340240D03*
X826368Y371019D03*
G54D42*
X119400Y638900D03*
X123100D03*
X207900Y637900D03*
X215406Y637892D03*
X228200Y639100D03*
X282600Y682100D03*
X258000Y653700D03*
X297767Y582318D03*
X294167D03*
X336631Y681726D03*
X370650Y190014D03*
X364600Y491900D03*
X849625Y177677D03*
X842984Y370969D03*
X893974Y179135D03*
X890639Y367560D03*
X878439Y400923D03*
G54D51*
X197087Y679921D03*
G54D33*
X123586Y460300D03*
Y465300D03*
Y470300D03*
Y475300D03*
Y480300D03*
Y485300D03*
Y490300D03*
Y495300D03*
X162144Y490300D03*
Y485300D03*
Y480300D03*
Y475300D03*
Y470300D03*
Y465300D03*
Y460300D03*
Y495300D03*
X220521Y460300D03*
Y465300D03*
Y470300D03*
Y475300D03*
Y480300D03*
Y485300D03*
Y490300D03*
X259079D03*
Y485300D03*
Y480300D03*
Y475300D03*
Y470300D03*
Y465300D03*
Y460300D03*
X220521Y495300D03*
X259079D03*
G54D108*
X856271Y393042D03*
X858240D03*
Y373756D03*
X856271D03*
X859779Y200908D03*
X861748D03*
X863716D03*
X865685D03*
X867653D03*
X869622D03*
X871591D03*
X873559D03*
X875528D03*
X877496D03*
X879465D03*
Y181622D03*
X877496D03*
X875528D03*
X873559D03*
X871591D03*
X869622D03*
X867653D03*
X865685D03*
X863716D03*
X861748D03*
X859779D03*
X860208Y393042D03*
X862177D03*
X864145D03*
X866114D03*
X868083D03*
X870051D03*
X872020D03*
X873988D03*
X875957D03*
Y373756D03*
X873988D03*
X872020D03*
X870051D03*
X868083D03*
X866114D03*
X864145D03*
X862177D03*
X860208D03*
G54D24*
X45052Y659909D03*
X182637Y463761D03*
X211800Y626900D03*
X148649Y687715D03*
X271900Y465400D03*
X258558Y589579D03*
X250525Y633776D03*
X275803Y704337D03*
X278200Y640772D03*
X263100Y666000D03*
X351282Y189778D03*
X293695Y539294D03*
X319600Y526100D03*
X284970Y637250D03*
X331800Y581394D03*
Y585000D03*
X389100Y541100D03*
X391011Y577031D03*
X370214Y639820D03*
X386100Y698000D03*
X379500Y710400D03*
X483026Y55778D03*
X493300Y38000D03*
X472386Y53022D03*
X552800Y61200D03*
X617847Y63107D03*
G54D60*
X244750Y666500D03*
X252250Y662625D03*
Y670375D03*
X244750Y652500D03*
X252250Y656375D03*
Y648625D03*
X361509Y175844D03*
X369009Y171969D03*
Y179719D03*
G54D15*
X34000Y48700D03*
X73768Y58955D03*
X93614Y501552D03*
X127300Y637700D03*
X73427Y689985D03*
X115619Y707195D03*
X283032Y730636D03*
X345034Y122812D03*
X352180Y636414D03*
X294018Y659982D03*
X539108Y69241D03*
X577404Y54967D03*
X598947Y63407D03*
X641347Y57407D03*
X603747Y62107D03*
X832572Y171877D03*
G54D25*
X64884Y643900D03*
X48284Y671800D03*
X211750Y634100D03*
X210500Y630600D03*
X148700Y691600D03*
X147417Y740048D03*
X275620Y715620D03*
X287000Y531100D03*
X305670Y612350D03*
X322300Y599000D03*
X288495Y576463D03*
X294804Y688120D03*
X286170Y644150D03*
X374104Y197291D03*
X362586Y639880D03*
X446135Y34357D03*
X707700Y423800D03*
X790600Y422800D03*
G54D43*
X119400Y642500D03*
X123100D03*
X207900Y641500D03*
X228200Y642700D03*
X215406Y641492D03*
X282600Y685700D03*
X258000Y657300D03*
X297767Y585918D03*
X294167D03*
X336631Y685326D03*
X370650Y193614D03*
X364600Y495500D03*
X849625Y181277D03*
X842984Y374569D03*
X893974Y182735D03*
X890639Y371160D03*
X878439Y404523D03*
G54D52*
X211732Y670886D03*
X207795D03*
X203858D03*
X209764Y688956D03*
X205827D03*
X223544Y670886D03*
X219607D03*
X215670D03*
X221575Y688956D03*
X217638D03*
X213701D03*
G54D109*
X862772Y111138D03*
X887572D03*
X862772Y90638D03*
X887572D03*
X898101Y283208D03*
X873301D03*
X898101Y303708D03*
X873301D03*
G54D70*
X355739Y565469D03*
Y562909D03*
Y560349D03*
Y557789D03*
Y555229D03*
Y552669D03*
Y550109D03*
Y547549D03*
X321324Y564683D03*
Y562123D03*
Y559563D03*
Y557003D03*
Y554443D03*
X299124D03*
Y557003D03*
Y559563D03*
Y562123D03*
Y564683D03*
X355739Y575709D03*
Y573149D03*
Y570589D03*
Y568029D03*
X321324Y577483D03*
Y574923D03*
Y572363D03*
Y569803D03*
Y567243D03*
X299124D03*
Y569803D03*
Y572363D03*
Y574923D03*
Y577483D03*
X352100Y673680D03*
Y676240D03*
Y678800D03*
Y681360D03*
Y683920D03*
Y686480D03*
Y689040D03*
Y691600D03*
Y694160D03*
Y696720D03*
X377939Y547549D03*
Y550109D03*
Y552669D03*
Y555229D03*
Y557789D03*
Y560349D03*
Y562909D03*
Y565469D03*
Y568029D03*
Y570589D03*
Y573149D03*
Y575709D03*
X374300Y696720D03*
Y694160D03*
Y691600D03*
Y689040D03*
Y686480D03*
Y683920D03*
Y681360D03*
Y678800D03*
Y676240D03*
Y673680D03*
G54D16*
X43000Y48500D03*
Y54500D03*
X82768Y58755D03*
Y64755D03*
X277600Y674600D03*
Y665600D03*
G54D34*
X119300Y518400D03*
X136000Y628900D03*
X81784Y671500D03*
X85400Y638516D03*
X188500Y693600D03*
X171747Y708475D03*
X258823Y628146D03*
X263000Y679300D03*
X243731Y705874D03*
X218623Y655646D03*
X225400Y716600D03*
X317600Y610400D03*
X322000Y645600D03*
X314720Y681820D03*
X311704Y715720D03*
X369400Y119500D03*
X523301Y54449D03*
X622537Y34526D03*
X589104Y43267D03*
X586647Y60807D03*
X669447Y37707D03*
X845625Y181177D03*
X838972Y374569D03*
G54D61*
X230315Y679921D03*
G54D44*
X135019Y714845D03*
G54D80*
X372000Y65400D03*
G54D26*
X61284Y643900D03*
X44684Y671800D03*
X208150Y634100D03*
X206900Y630600D03*
X145100Y691600D03*
X143817Y740048D03*
X283400Y531100D03*
X282570Y644150D03*
X272020Y715620D03*
X302070Y612350D03*
X318700Y599000D03*
X284895Y576463D03*
X291204Y688120D03*
X370504Y197291D03*
X358986Y639880D03*
X442535Y34357D03*
X704100Y423800D03*
X787000Y422800D03*
G54D62*
X267100Y671900D03*
Y668300D03*
X303100Y661630D03*
Y658030D03*
G54D17*
X51000Y52000D03*
X62000D03*
X90768Y62255D03*
X101768D03*
X243199Y718747D03*
X232199D03*
X243199Y728347D03*
X232199D03*
X243199Y737947D03*
X232199D03*
X605847Y77007D03*
X594847D03*
G54D71*
X298219Y527239D03*
Y529209D03*
Y531179D03*
Y533149D03*
X307419D03*
Y531179D03*
Y529209D03*
Y527239D03*
X377739Y515004D03*
Y513039D03*
Y511069D03*
Y509099D03*
Y507134D03*
X361439D03*
Y509099D03*
Y511069D03*
Y513039D03*
Y515004D03*
G36*
G01X175989Y669266D02*
G02Y669316I-12800J25D01*
G01X171589D01*
G03Y669266I-8400J-25D01*
G01X175989D01*
G37*
G54D35*
X119300Y514800D03*
X136000Y625300D03*
X85400Y634916D03*
X81784Y667900D03*
X188500Y690000D03*
X171747Y704875D03*
X258823Y624546D03*
X263000Y675700D03*
X243731Y702274D03*
X218623Y652046D03*
X225400Y713000D03*
X317600Y606800D03*
X322000Y642000D03*
X314720Y678220D03*
X311704Y712120D03*
X369400Y115900D03*
X523301Y50849D03*
X622537Y30926D03*
X589104Y39667D03*
X586647Y57207D03*
X669447Y34107D03*
X845625Y177577D03*
X838972Y370969D03*
G54D27*
X65714Y665850D03*
X306300Y638600D03*
X295634Y710070D03*
G54D54*
X197920Y712091D03*
Y736891D03*
X367700Y136500D03*
Y161300D03*
G54D63*
X275956Y653733D03*
X268456Y649858D03*
Y657608D03*
X346850Y662500D03*
X339350Y666375D03*
Y658625D03*
X496678Y61151D03*
X489178Y57276D03*
Y65026D03*
X710550Y30775D03*
Y23025D03*
X718050Y26900D03*
G54D90*
X530998Y64511D03*
Y78351D03*
G54D36*
X135012Y521048D03*
X125788D03*
X135012Y514552D03*
X125788D03*
X270521Y612019D03*
X279745D03*
X270521Y618515D03*
X279745D03*
G54D72*
X312262Y593351D03*
Y590791D03*
Y588231D03*
X318762D03*
Y593351D03*
X337750Y591440D03*
Y594000D03*
Y596560D03*
X331250D03*
Y591440D03*
G54D45*
X125376Y705002D03*
Y706971D03*
Y708939D03*
Y710908D03*
Y712876D03*
Y714845D03*
Y716814D03*
Y718782D03*
Y720751D03*
Y722719D03*
Y724688D03*
X144662Y708939D03*
Y706971D03*
Y705002D03*
Y724688D03*
Y722719D03*
Y720751D03*
Y718782D03*
Y716814D03*
Y714845D03*
Y712876D03*
Y710908D03*
G54D81*
X357290Y624270D03*
X373038D03*
Y600970D03*
X357290D03*
G54D18*
X30900Y79600D03*
X81169Y734566D03*
X145053Y647840D03*
X271068Y529401D03*
X847271Y45720D03*
G54D19*
X44206Y543876D03*
X36758Y543881D03*
X44187Y555153D03*
X36687D03*
X44000Y549500D03*
X36500D03*
X44206Y538249D03*
X36658Y538254D03*
X44106Y532622D03*
X64746Y647850D03*
X130400Y534600D03*
X140300Y529700D03*
X130400Y530300D03*
X140467Y537795D03*
X121803Y613818D03*
X126700Y599000D03*
X182439Y474031D03*
X212100Y495300D03*
X149692Y519686D03*
Y515686D03*
X203300Y503300D03*
X191528Y643963D03*
X148549Y683715D03*
X158549Y711215D03*
X271400Y474380D03*
X284445Y561694D03*
X251396Y557061D03*
X251477Y563068D03*
X267400Y553100D03*
X275825Y541121D03*
X242996Y560398D03*
Y564498D03*
X243300Y601000D03*
X243700Y589800D03*
X236100Y634300D03*
X252100Y578300D03*
X251100Y585700D03*
X252000Y573500D03*
X254125Y567260D03*
X272119Y574462D03*
X262976Y669731D03*
X238889Y662667D03*
X275420Y719420D03*
X351182Y193578D03*
X351482Y178678D03*
Y257778D03*
X343718Y232181D03*
X348500Y543800D03*
X351261Y507831D03*
X286900Y527300D03*
X287000Y522800D03*
Y535000D03*
X306453Y620550D03*
X299715Y592831D03*
X314644Y582263D03*
X348066Y594759D03*
X344200Y585500D03*
X294782Y691947D03*
X286070Y647978D03*
Y652044D03*
X345600Y672000D03*
X370680Y245508D03*
X365881Y225861D03*
X370680Y241308D03*
X367661Y475491D03*
X363002Y480368D03*
X389200Y533400D03*
X389800Y564400D03*
X366064Y635920D03*
X391200Y613900D03*
X393000Y597200D03*
X392581Y622265D03*
X493200Y42000D03*
X493600Y34000D03*
X482926Y59562D03*
X489214Y51841D03*
X589420Y50435D03*
X653746Y521683D03*
X653783Y530195D03*
X657078Y517560D03*
X737200Y426800D03*
X850011Y165178D03*
X852368Y207864D03*
Y211864D03*
X849456Y344740D03*
X848860Y403998D03*
Y395998D03*
Y399998D03*
X820100Y425800D03*
G54D37*
X125600Y630800D03*
Y623200D03*
X79050Y637546D03*
Y629946D03*
X133600Y637700D03*
X91550Y654554D03*
Y662154D03*
X83750Y654654D03*
Y662254D03*
X133600Y645300D03*
X117149Y730715D03*
Y738315D03*
X109449Y730715D03*
Y738315D03*
X124820Y732391D03*
Y739991D03*
X94020Y730691D03*
Y738291D03*
X101749Y730715D03*
Y738315D03*
X132651Y732415D03*
Y740015D03*
X211800Y710100D03*
Y717700D03*
X219600Y710100D03*
Y717700D03*
X333500Y111200D03*
Y118800D03*
X332436Y627504D03*
Y635104D03*
X324636Y627604D03*
Y635204D03*
X311936Y609096D03*
Y601496D03*
X309236Y658404D03*
Y666004D03*
X317136Y658404D03*
Y666004D03*
X313870Y699174D03*
Y706774D03*
X321670Y699074D03*
Y706674D03*
X309100Y682800D03*
Y675200D03*
X306370Y731174D03*
Y738774D03*
X298470Y731174D03*
Y738774D03*
X663847Y39907D03*
Y32307D03*
X655847Y39907D03*
Y32307D03*
X898622Y76514D03*
Y68914D03*
X890622Y76514D03*
Y68914D03*
X882622Y76514D03*
Y68914D03*
X899491Y398439D03*
Y406039D03*
X891794Y398441D03*
Y406041D03*
X884102Y398456D03*
Y406056D03*
X899597Y384357D03*
Y391957D03*
G54D91*
X536993Y54351D03*
Y47945D03*
G54D55*
X180190Y728775D03*
X158304D03*
G54D28*
X68273Y656107D03*
X65714D03*
X63155D03*
X60596D03*
Y675593D03*
X63155D03*
X65714D03*
X68273D03*
X70832Y656107D03*
Y675593D03*
X311418Y628857D03*
X308859D03*
X306300D03*
X303741D03*
X301182D03*
X300752Y700327D03*
X298193D03*
X295634D03*
X293075D03*
X290516D03*
X301182Y648343D03*
X303741D03*
X306300D03*
X308859D03*
X311418D03*
X290516Y719813D03*
X293075D03*
X295634D03*
X298193D03*
X300752D03*
G54D73*
X353514Y604746D03*
Y620494D03*
X376814D03*
Y604746D03*
G54D46*
X134700Y694750D03*
G54D64*
X354000Y119740D03*
Y116000D03*
Y112260D03*
X357800Y706700D03*
Y702960D03*
Y710440D03*
X363000Y112260D03*
Y119740D03*
X366800Y702960D03*
Y710440D03*
G54D82*
X359258Y623920D03*
X361227D03*
X363195D03*
X365164D03*
X367133D03*
X369101D03*
X371070D03*
Y601320D03*
X369101D03*
X367133D03*
X365164D03*
X363195D03*
X361227D03*
X359258D03*
G54D83*
X365164Y612620D03*
G54D38*
X90854Y639150D03*
X98454D03*
X86983Y674124D03*
X94583D03*
X86983Y682024D03*
X94583D03*
X90854Y647050D03*
X98454D03*
X87900Y722700D03*
X95500D03*
X243324Y623114D03*
X250924D03*
X322740Y619400D03*
X330340D03*
X322740Y611500D03*
X330340D03*
X320774Y684270D03*
X328374D03*
X320774Y691970D03*
X328374D03*
X514972Y26680D03*
X522572D03*
X503854Y42093D03*
X511454D03*
X511465Y34432D03*
X503865D03*
X609257Y23971D03*
X616857D03*
X613247Y77407D03*
X620847D03*
X613247Y69307D03*
X620847D03*
X888313Y201350D03*
X895913D03*
X887184Y192800D03*
X894784D03*
X885492Y209135D03*
X893092D03*
X885492Y216835D03*
X893092D03*
X891166Y381316D03*
X883566D03*
G54D92*
X544495Y54351D03*
Y47945D03*
G54D29*
X55971Y660732D03*
Y663291D03*
Y665850D03*
Y668409D03*
Y670968D03*
X75457D03*
Y668409D03*
Y665850D03*
Y663291D03*
Y660732D03*
X296557Y633482D03*
Y636041D03*
X316043D03*
Y633482D03*
X285891Y704952D03*
Y707511D03*
X305377D03*
Y704952D03*
X296557Y638600D03*
Y641159D03*
Y643718D03*
X316043D03*
Y641159D03*
Y638600D03*
X285891Y710070D03*
Y712629D03*
Y715188D03*
X305377D03*
Y712629D03*
Y710070D03*
G54D56*
X281645Y546834D03*
Y549394D03*
Y551954D03*
X274245D03*
Y549394D03*
Y546834D03*
G54D74*
X353864Y606714D03*
Y608683D03*
Y610651D03*
Y612620D03*
Y614589D03*
Y616557D03*
Y618526D03*
X376464D03*
Y616557D03*
Y614589D03*
Y612620D03*
Y610651D03*
Y608683D03*
Y606714D03*
G54D65*
X350737Y104200D03*
X372770Y52800D03*
Y48200D03*
X372470Y86300D03*
Y81700D03*
G54D47*
X134700Y697450D03*
G54D84*
X369273Y645871D03*
X360049D03*
Y651827D03*
X369273D03*
G54D93*
X531093Y39133D03*
Y34133D03*
Y29133D03*
Y24133D03*
G54D66*
X353737Y104200D03*
X375770Y52800D03*
Y48200D03*
X375470Y86300D03*
Y81700D03*
G54D57*
X250624Y629614D03*
X786900Y25000D03*
X851620Y366572D03*
X866768Y210564D03*
X863120Y405672D03*
G54D75*
X328600Y665850D03*
X324725Y658350D03*
X332475D03*
G54D39*
X140090Y621027D03*
X202800Y510100D03*
X208100Y515200D03*
X208000Y520500D03*
X178800Y513400D03*
X160100Y622300D03*
X161900Y627800D03*
X167400Y618300D03*
X165800Y623700D03*
X206636Y618649D03*
X241100Y544100D03*
X238100Y550800D03*
X247300Y544000D03*
X235700Y544500D03*
X237980Y555707D03*
X217134Y521103D03*
X238168Y529269D03*
X235658Y534262D03*
X221898Y618622D03*
X235614Y609978D03*
X369100Y592006D03*
X740900Y553600D03*
X741000Y547700D03*
X830426Y482939D03*
X835949Y482890D03*
G54D48*
X154724Y537795D03*
Y540945D03*
Y544094D03*
X157874Y537795D03*
Y540945D03*
Y544094D03*
X161023Y537795D03*
Y540945D03*
Y544094D03*
X154724Y597638D03*
Y600787D03*
Y603937D03*
X157874Y597638D03*
Y600787D03*
Y603937D03*
X161023Y597638D03*
Y600787D03*
Y603937D03*
X214567Y537795D03*
Y540945D03*
Y544094D03*
X217716Y537795D03*
Y540945D03*
Y544094D03*
X220866Y537795D03*
Y540945D03*
Y544094D03*
X214567Y597638D03*
Y600787D03*
Y603937D03*
X217716Y597638D03*
Y600787D03*
Y603937D03*
X220866Y597638D03*
Y600787D03*
Y603937D03*
G54D49*
X169149Y691815D03*
X357882Y185174D03*
X450488Y54522D03*
X433255Y47144D03*
X433257Y42488D03*
X433246Y51800D03*
X579304Y45967D03*
X603447Y30307D03*
X781400Y29800D03*
X840322Y160314D03*
X848622Y145014D03*
X844706Y340240D03*
X820768Y371019D03*
G54D67*
X356611Y199968D03*
X351611D03*
X346611D03*
X341611D03*
Y219968D03*
X346611D03*
X351611D03*
X356611D03*
G54D85*
X461110Y45450D03*
X474890D03*
Y25350D03*
X461110D03*
X603051Y51073D03*
X608957D03*
Y38861D03*
X603051D03*
G54D58*
X245024Y629614D03*
X781300Y25000D03*
X857520Y405672D03*
X846020Y366572D03*
X861168Y210564D03*
G54D94*
X606004Y44967D03*
G54D76*
X372000Y62400D03*
G54D59*
X251091Y692774D03*
X248531D03*
X245971D03*
Y686274D03*
X251091D03*
X271240Y686350D03*
X273800D03*
X276360D03*
Y692850D03*
X271240D03*
X263491Y692574D03*
X260931D03*
X258371D03*
Y686074D03*
X263491D03*
X363975Y203549D03*
X369095D03*
Y210049D03*
X366535D03*
X363975D03*
X370140Y487250D03*
X372700D03*
X375260D03*
Y493750D03*
X370140D03*
G54D77*
X391358Y75749D03*
Y69149D03*
X387558D03*
Y75749D03*
G54D95*
X605020Y51023D03*
X606988D03*
Y38911D03*
X605020D03*
G54D68*
X297146Y205315D03*
Y202165D03*
Y199016D03*
Y195866D03*
Y192717D03*
X314666Y205315D03*
Y202165D03*
Y199016D03*
Y195866D03*
Y192717D03*
X297146Y277756D03*
Y274606D03*
Y271457D03*
Y268307D03*
Y265158D03*
Y262008D03*
Y258858D03*
Y255709D03*
Y252559D03*
Y249410D03*
Y246260D03*
Y243110D03*
Y239961D03*
Y236811D03*
Y233661D03*
Y230512D03*
Y227362D03*
Y224213D03*
Y221063D03*
Y217913D03*
Y214764D03*
Y211614D03*
Y208465D03*
X314666Y277756D03*
Y274606D03*
Y271457D03*
Y268307D03*
Y265158D03*
Y262008D03*
Y258858D03*
Y255709D03*
Y252559D03*
Y249410D03*
Y246260D03*
Y243110D03*
Y239961D03*
Y236811D03*
Y233661D03*
Y230512D03*
Y227362D03*
Y224213D03*
Y221063D03*
Y217913D03*
Y214764D03*
Y211614D03*
Y208465D03*
X297146Y350197D03*
Y347047D03*
Y343898D03*
Y340748D03*
Y337599D03*
Y334449D03*
Y331299D03*
Y328150D03*
Y325000D03*
Y321850D03*
Y318701D03*
Y315551D03*
Y312402D03*
Y309252D03*
Y306102D03*
Y302953D03*
Y299803D03*
Y296654D03*
Y293504D03*
Y290354D03*
Y287205D03*
Y284055D03*
Y280906D03*
X314666Y350197D03*
Y347047D03*
Y343898D03*
Y340748D03*
Y337599D03*
Y334449D03*
Y331299D03*
Y328150D03*
Y325000D03*
Y321850D03*
Y318701D03*
Y315551D03*
Y312402D03*
Y309252D03*
Y306102D03*
Y302953D03*
Y299803D03*
Y296654D03*
Y293504D03*
Y290354D03*
Y287205D03*
Y284055D03*
Y280906D03*
X297146Y378543D03*
Y375394D03*
Y372244D03*
Y369095D03*
Y365945D03*
Y362795D03*
Y359646D03*
Y356496D03*
Y353347D03*
X314666Y378543D03*
Y375394D03*
Y372244D03*
Y369095D03*
Y365945D03*
Y362795D03*
Y359646D03*
Y356496D03*
Y353347D03*
G54D86*
X463079Y45150D03*
X465047D03*
X467016D03*
X468984D03*
X470953D03*
X472921D03*
Y25650D03*
X470953D03*
X468984D03*
X467016D03*
X465047D03*
X463079D03*
G54D69*
X351285Y233565D03*
X365125D03*
G54D96*
X612060Y45951D03*
Y43983D03*
X599948D03*
Y45951D03*
G54D87*
X478050Y42290D03*
Y28510D03*
X457950D03*
Y42290D03*
X612110Y47920D03*
Y42014D03*
X599898D03*
Y47920D03*
G54D78*
X372000Y71800D03*
G54D88*
X477750Y40321D03*
Y38353D03*
Y36384D03*
Y34416D03*
Y32447D03*
Y30479D03*
X458250D03*
Y32447D03*
Y34416D03*
Y36384D03*
Y38353D03*
Y40321D03*
G54D79*
X372000Y68800D03*
G54D97*
X588647Y35157D03*
G54D89*
X468000Y35400D03*
G54D98*
X588647Y32457D03*
G54D99*
X646021Y42707D03*
X630273D03*
M02*
